FILE_TYPE = MACRO_DRAWING;
SET COLOR_WIRE YELLOW;
SET COLOR_PROP ORANGE;
SET COLOR_DOT WHITE;
SET COLOR_ARC YELLOW;
SET COLOR_BODY GREEN;
SET COLOR_NOTE PURPLE;
SET PROP_DISPLAY VALUE;
SET PAGE_NUMBER P29;
SET PATH_NUMBER P222;
FORCEADD UNIVERSAL_GND..1
(-1125 500);
FORCEPROP 3 LASTPIN (-1125 550) SIG_NAME GND\g
J 0
(-1115 560);
DISPLAY 0.659574 (-1115 560);
PAINT MONO (-1115 560);
DISPLAY INVISIBLE (-1115 560);
FORCEPROP 1 LAST HDL_POWER GND
J 1
(-1100 425);
DISPLAY 0.702128 (-1100 425);
PAINT GREEN (-1100 425);
FORCEPROP 1 LAST PATH I100
J 0
(-1050 500);
DISPLAY 0.872340 (-1050 500);
PAINT AQUA (-1050 500);
DISPLAY INVISIBLE (-1050 500);
FORCEPROP 2 LAST CDS_LIB logical_power
J 0
(-1125 500);
DISPLAY INVISIBLE (-1125 500);
FORCEADD Q_RES..1
(-2250 1115);
FORCEPROP 1 LAST TOLERANCE 5%
J 0
(-2250 1065);
DISPLAY 0.510638 (-2250 1065);
PAINT SKYBLUE (-2250 1065);
FORCEPROP 1 LAST VALUE 0
J 2
(-2275 1065);
DISPLAY 0.510638 (-2275 1065);
PAINT SKYBLUE (-2275 1065);
FORCEPROP 1 LAST PART_NUMBER CS00002JB13
J 0
(-2300 1215);
DISPLAY 0.510638 (-2300 1215);
PAINT WHITE (-2300 1215);
FORCEPROP 1 LAST PACK_TYPE 0402LF
J 0
(-2050 1015);
DISPLAY 0.510638 (-2050 1015);
PAINT SKYBLUE (-2050 1015);
FORCEPROP 1 LAST WATTAGE 1/16W
J 2
(-2275 1015);
DISPLAY 0.510638 (-2275 1015);
PAINT SKYBLUE (-2275 1015);
FORCEPROP 1 LAST MATERIAL CHIP
J 0
(-2250 1015);
DISPLAY 0.510638 (-2250 1015);
PAINT SKYBLUE (-2250 1015);
FORCEPROP 1 LAST PATH I101
J 0
(-2300 1265);
DISPLAY 0.978723 (-2300 1265);
PAINT WHITE (-2300 1265);
DISPLAY INVISIBLE (-2300 1265);
FORCEPROP 2 LAST CDS_LIB pure_quanta
J 0
(-2250 1115);
PAINT RED (-2250 1115);
DISPLAY INVISIBLE (-2250 1115);
FORCEPROP 1 LAST LOCATION R386
J 0
(-2300 1165);
DISPLAY 0.702128 (-2300 1165);
PAINT YELLOW (-2300 1165);
FORCEPROP 1 LASTPIN (-2350 1115) $PN 1
J 0
(-2338 1127);
DISPLAY 0.808511 (-2338 1127);
PAINT WHITE (-2338 1127);
FORCEPROP 1 LASTPIN (-2150 1115) $PN 2
J 0
(-2188 1127);
DISPLAY 0.808511 (-2188 1127);
PAINT WHITE (-2188 1127);
FORCEPROP 2 LAST $SEC 1
J 0
(-2300 1315);
DISPLAY 0.680851 (-2300 1315);
PAINT MONO (-2300 1315);
DISPLAY INVISIBLE (-2300 1315);
FORCEPROP 2 LAST CDS_SEC 1
J 0
(-2300 1315);
DISPLAY 1.021277 (-2300 1315);
DISPLAY INVISIBLE (-2300 1315);
FORCEADD Q_INDUCTOR4P_12..1
R 6
(-2400 1675);
FORCEPROP 2 LAST VALUE 67/320MA
J 0
(-2600 1327);
DISPLAY 0.510638 (-2600 1327);
PAINT SKYBLUE (-2600 1327);
FORCEPROP 1 LAST MATERIAL EMPTY
J 0
(-2624 1481);
DISPLAY 0.510638 (-2624 1481);
PAINT RED (-2624 1481);
FORCEPROP 2 LAST PART_TYPE SMLF
J 0
(-2600 1277);
DISPLAY 0.510638 (-2600 1277);
PAINT SKYBLUE (-2600 1277);
FORCEPROP 1 LAST PART_NUMBER CX21SN67000
J 0
(-2624 1429);
DISPLAY 0.510638 (-2624 1429);
PAINT WHITE (-2624 1429);
FORCEPROP 2 LAST CURRENT_AMP 320MA
J 0
(-2600 1227);
DISPLAY 1.021277 (-2600 1227);
FORCEPROP 1 LAST PATH I102
J 0
(-2400 1675);
DISPLAY 0.723404 (-2400 1675);
PAINT GREEN (-2400 1675);
DISPLAY INVISIBLE (-2400 1675);
FORCEPROP 1 LAST NEEDS_NO_SIZE TRUE
J 0
(-2150 1828);
DISPLAY 0.468085 (-2150 1828);
PAINT GREEN (-2150 1828);
DISPLAY INVISIBLE (-2150 1828);
FORCEPROP 1 LAST CDS_LMAN_SYM_OUTLINE -250,175,250,-175
J 0
(-2400 1653);
DISPLAY 0.468085 (-2400 1653);
PAINT GREEN (-2400 1653);
DISPLAY INVISIBLE (-2400 1653);
FORCEPROP 2 LAST CDS_LIB pure_quanta
J 0
(-2400 1628);
PAINT MONO (-2400 1628);
DISPLAY INVISIBLE (-2400 1628);
FORCEPROP 1 LAST LOCATION L23
J 0
(-2624 1388);
DISPLAY 0.702128 (-2624 1388);
PAINT YELLOW (-2624 1388);
FORCEPROP 0 LASTPIN (-2800 1550) $PN 1
J 2
(-2810 1560);
DISPLAY 0.680851 (-2810 1560);
PAINT MONO (-2810 1560);
FORCEPROP 0 LASTPIN (-2000 1550) $PN 2
J 0
(-1990 1560);
DISPLAY 0.680851 (-1990 1560);
PAINT MONO (-1990 1560);
FORCEPROP 0 LASTPIN (-2000 1800) $PN 3
J 0
(-1990 1810);
DISPLAY 0.680851 (-1990 1810);
PAINT MONO (-1990 1810);
FORCEPROP 0 LASTPIN (-2800 1800) $PN 4
J 2
(-2810 1810);
DISPLAY 0.680851 (-2810 1810);
PAINT MONO (-2810 1810);
FORCEPROP 2 LAST $SEC 1
J 0
(-2600 1193);
DISPLAY 0.680851 (-2600 1193);
PAINT MONO (-2600 1193);
DISPLAY INVISIBLE (-2600 1193);
FORCEPROP 2 LAST CDS_SEC 1
J 0
(-2600 1177);
DISPLAY 1.021277 (-2600 1177);
DISPLAY INVISIBLE (-2600 1177);
FORCEADD OFFPAGE..6
(-3525 1800);
FORCEPROP 2 LAST $XR0 10 
J 0
(-3774 1800);
DISPLAY 0.638298 (-3774 1800);
PAINT MONO (-3774 1800);
FORCEPROP 2 LAST PATH I103
J 0
(-3750 1850);
DISPLAY 0.680851 (-3750 1850);
DISPLAY INVISIBLE (-3750 1850);
FORCEPROP 1 LAST COMMENT_BODY TRUE
J 0
(-3425 1725);
DISPLAY 0.872340 (-3425 1725);
PAINT PEACH (-3425 1725);
DISPLAY INVISIBLE (-3425 1725);
FORCEPROP 1 LAST OFFPAGE TRUE
J 0
(-3200 1675);
DISPLAY 0.872340 (-3200 1675);
PAINT GREEN (-3200 1675);
DISPLAY INVISIBLE (-3200 1675);
FORCEPROP 2 LAST CDS_LIB standard
J 0
(-3525 1800);
PAINT RED (-3525 1800);
DISPLAY INVISIBLE (-3525 1800);
FORCEADD OFFPAGE..6
(-3525 1550);
FORCEPROP 2 LAST $XR0 10 
J 0
(-3774 1550);
DISPLAY 0.638298 (-3774 1550);
PAINT MONO (-3774 1550);
FORCEPROP 2 LAST PATH I104
J 0
(-3750 1600);
DISPLAY 0.680851 (-3750 1600);
DISPLAY INVISIBLE (-3750 1600);
FORCEPROP 1 LAST COMMENT_BODY TRUE
J 0
(-3425 1475);
DISPLAY 0.872340 (-3425 1475);
PAINT PEACH (-3425 1475);
DISPLAY INVISIBLE (-3425 1475);
FORCEPROP 1 LAST OFFPAGE TRUE
J 0
(-3200 1425);
DISPLAY 0.872340 (-3200 1425);
PAINT GREEN (-3200 1425);
DISPLAY INVISIBLE (-3200 1425);
FORCEPROP 2 LAST CDS_LIB standard
J 0
(-3525 1550);
PAINT RED (-3525 1550);
DISPLAY INVISIBLE (-3525 1550);
FORCEADD OFFPAGE..5
R 2
(400 2650);
FORCEPROP 2 LAST $XR0 29 
J 0
(589 2650);
DISPLAY 0.638298 (589 2650);
PAINT MONO (589 2650);
FORCEPROP 2 LAST CDS_LIB standard
J 2
(400 2650);
DISPLAY INVISIBLE (400 2650);
FORCEPROP 1 LAST OFFPAGE TRUE
J 2
(75 2525);
DISPLAY 0.872340 (75 2525);
PAINT GREEN (75 2525);
DISPLAY INVISIBLE (75 2525);
FORCEPROP 1 LAST COMMENT_BODY TRUE
J 2
(300 2575);
DISPLAY 0.872340 (300 2575);
PAINT PEACH (300 2575);
DISPLAY INVISIBLE (300 2575);
FORCEPROP 2 LAST PATH I105
J 0
(600 2700);
DISPLAY 0.680851 (600 2700);
DISPLAY INVISIBLE (600 2700);
FORCEADD OFFPAGE..5
R 2
(400 2400);
FORCEPROP 2 LAST $XR0 29 
J 0
(589 2400);
DISPLAY 0.638298 (589 2400);
PAINT MONO (589 2400);
FORCEPROP 2 LAST CDS_LIB standard
J 2
(400 2400);
DISPLAY INVISIBLE (400 2400);
FORCEPROP 1 LAST OFFPAGE TRUE
J 2
(75 2275);
DISPLAY 0.872340 (75 2275);
PAINT GREEN (75 2275);
DISPLAY INVISIBLE (75 2275);
FORCEPROP 1 LAST COMMENT_BODY TRUE
J 2
(300 2325);
DISPLAY 0.872340 (300 2325);
PAINT PEACH (300 2325);
DISPLAY INVISIBLE (300 2325);
FORCEPROP 2 LAST PATH I106
J 0
(600 2450);
DISPLAY 0.680851 (600 2450);
DISPLAY INVISIBLE (600 2450);
FORCEADD Q_RES..1
R 2
(-900 2925);
FORCEPROP 1 LAST WATTAGE 1/16W
J 0
(-875 2825);
DISPLAY 0.510638 (-875 2825);
PAINT SKYBLUE (-875 2825);
FORCEPROP 1 LAST VALUE 0
J 0
(-875 2875);
DISPLAY 0.510638 (-875 2875);
PAINT SKYBLUE (-875 2875);
FORCEPROP 1 LAST PACK_TYPE 0402LF
J 2
(-1100 2825);
DISPLAY 0.510638 (-1100 2825);
PAINT SKYBLUE (-1100 2825);
FORCEPROP 1 LAST TOLERANCE 5%
J 2
(-900 2875);
DISPLAY 0.510638 (-900 2875);
PAINT SKYBLUE (-900 2875);
FORCEPROP 1 LAST MATERIAL CHIP
J 2
(-900 2825);
DISPLAY 0.510638 (-900 2825);
PAINT SKYBLUE (-900 2825);
FORCEPROP 1 LAST PART_NUMBER CS00002JB13
J 2
(-850 3025);
DISPLAY 0.510638 (-850 3025);
PAINT WHITE (-850 3025);
FORCEPROP 2 LAST CDS_LIB pure_quanta
J 2
(-900 2925);
DISPLAY INVISIBLE (-900 2925);
FORCEPROP 1 LAST PATH I109
J 2
(-850 3075);
DISPLAY 0.978723 (-850 3075);
PAINT WHITE (-850 3075);
DISPLAY INVISIBLE (-850 3075);
FORCEPROP 1 LAST LOCATION R675
J 2
(-850 2975);
DISPLAY 0.702128 (-850 2975);
PAINT YELLOW (-850 2975);
FORCEPROP 0 LAST $SEC 1
J 2
(-850 3050);
DISPLAY 0.680851 (-850 3050);
PAINT MONO (-850 3050);
DISPLAY INVISIBLE (-850 3050);
FORCEPROP 0 LAST CDS_SEC 1
J 2
(-850 3050);
DISPLAY 1.021277 (-850 3050);
DISPLAY INVISIBLE (-850 3050);
FORCEPROP 1 LASTPIN (-800 2925) $PN 1
J 2
(-812 2937);
DISPLAY 0.808511 (-812 2937);
PAINT WHITE (-812 2937);
DISPLAY INVISIBLE (-812 2937);
FORCEPROP 1 LASTPIN (-1000 2925) $PN 2
J 2
(-962 2937);
DISPLAY 0.808511 (-962 2937);
PAINT WHITE (-962 2937);
DISPLAY INVISIBLE (-962 2937);
FORCEADD Q_RES..1
R 2
(-800 2075);
FORCEPROP 1 LAST VALUE 0
J 0
(-775 2025);
DISPLAY 0.510638 (-775 2025);
PAINT SKYBLUE (-775 2025);
FORCEPROP 1 LAST TOLERANCE 5%
J 2
(-800 2025);
DISPLAY 0.510638 (-800 2025);
PAINT SKYBLUE (-800 2025);
FORCEPROP 1 LAST MATERIAL CHIP
J 2
(-800 1975);
DISPLAY 0.510638 (-800 1975);
PAINT SKYBLUE (-800 1975);
FORCEPROP 1 LAST PART_NUMBER CS00002JB13
J 2
(-750 2175);
DISPLAY 0.510638 (-750 2175);
PAINT WHITE (-750 2175);
FORCEPROP 1 LAST PACK_TYPE 0402LF
J 2
(-1000 1975);
DISPLAY 0.510638 (-1000 1975);
PAINT SKYBLUE (-1000 1975);
FORCEPROP 1 LAST WATTAGE 1/16W
J 0
(-775 1975);
DISPLAY 0.510638 (-775 1975);
PAINT SKYBLUE (-775 1975);
FORCEPROP 2 LAST CDS_LIB pure_quanta
J 2
(-800 2075);
DISPLAY INVISIBLE (-800 2075);
FORCEPROP 1 LAST PATH I111
J 2
(-750 2225);
DISPLAY 0.978723 (-750 2225);
PAINT WHITE (-750 2225);
DISPLAY INVISIBLE (-750 2225);
FORCEPROP 1 LAST LOCATION R668
J 2
(-750 2125);
DISPLAY 0.702128 (-750 2125);
PAINT YELLOW (-750 2125);
FORCEPROP 0 LAST $SEC 1
J 2
(-750 2200);
DISPLAY 0.680851 (-750 2200);
PAINT MONO (-750 2200);
DISPLAY INVISIBLE (-750 2200);
FORCEPROP 0 LAST CDS_SEC 1
J 2
(-750 2200);
DISPLAY 1.021277 (-750 2200);
DISPLAY INVISIBLE (-750 2200);
FORCEPROP 1 LASTPIN (-700 2075) $PN 1
J 2
(-712 2087);
DISPLAY 0.808511 (-712 2087);
PAINT WHITE (-712 2087);
DISPLAY INVISIBLE (-712 2087);
FORCEPROP 1 LASTPIN (-900 2075) $PN 2
J 2
(-862 2087);
DISPLAY 0.808511 (-862 2087);
PAINT WHITE (-862 2087);
DISPLAY INVISIBLE (-862 2087);
FORCEADD Q_INDUCTOR4P_12..1
R 2
(-875 2500);
FORCEPROP 1 LAST MATERIAL EMPTY
J 2
(-651 2310);
DISPLAY 0.510638 (-651 2310);
PAINT RED (-651 2310);
FORCEPROP 2 LAST PART_TYPE SMLF
J 2
(-1050 2250);
DISPLAY 0.510638 (-1050 2250);
PAINT SKYBLUE (-1050 2250);
FORCEPROP 2 LAST CURRENT_AMP 320MA
J 2
(-1050 2200);
DISPLAY 0.680851 (-1050 2200);
FORCEPROP 1 LAST PART_NUMBER CX21SN67000
J 2
(-651 2262);
DISPLAY 0.510638 (-651 2262);
PAINT WHITE (-651 2262);
FORCEPROP 2 LAST VALUE 67/320MA
J 2
(-1050 2300);
DISPLAY 0.510638 (-1050 2300);
PAINT SKYBLUE (-1050 2300);
FORCEPROP 1 LAST NEEDS_NO_SIZE TRUE
J 2
(-1125 2325);
DISPLAY 0.468085 (-1125 2325);
PAINT GREEN (-1125 2325);
DISPLAY INVISIBLE (-1125 2325);
FORCEPROP 1 LAST CDS_LMAN_SYM_OUTLINE -250,175,250,-175
J 2
(-875 2500);
DISPLAY 0.468085 (-875 2500);
PAINT GREEN (-875 2500);
DISPLAY INVISIBLE (-875 2500);
FORCEPROP 2 LAST CDS_LIB pure_quanta
J 2
(-875 2500);
DISPLAY INVISIBLE (-875 2500);
FORCEPROP 1 LAST PATH I113
J 2
(-875 2500);
DISPLAY 0.723404 (-875 2500);
PAINT GREEN (-875 2500);
DISPLAY INVISIBLE (-875 2500);
FORCEPROP 1 LAST LOCATION L22
J 2
(-651 2755);
DISPLAY 0.702128 (-651 2755);
PAINT YELLOW (-651 2755);
FORCEPROP 0 LASTPIN (-475 2625) $PN 1
J 0
(-465 2635);
DISPLAY 0.680851 (-465 2635);
PAINT MONO (-465 2635);
FORCEPROP 0 LASTPIN (-1275 2625) $PN 2
J 2
(-1285 2635);
DISPLAY 0.680851 (-1285 2635);
PAINT MONO (-1285 2635);
FORCEPROP 0 LASTPIN (-1275 2375) $PN 3
J 2
(-1285 2385);
DISPLAY 0.680851 (-1285 2385);
PAINT MONO (-1285 2385);
FORCEPROP 0 LASTPIN (-475 2375) $PN 4
J 0
(-465 2385);
DISPLAY 0.680851 (-465 2385);
PAINT MONO (-465 2385);
FORCEPROP 0 LAST $SEC 1
J 2
(-675 2800);
DISPLAY 0.680851 (-675 2800);
PAINT MONO (-675 2800);
DISPLAY INVISIBLE (-675 2800);
FORCEPROP 0 LAST CDS_SEC 1
J 2
(-675 2800);
DISPLAY 1.021277 (-675 2800);
DISPLAY INVISIBLE (-675 2800);
FORCEADD OFFPAGE..4
R 2
(-3900 2375);
FORCEPROP 2 LAST $XR0 29 
J 0
(-4151 2375);
DISPLAY 0.638298 (-4151 2375);
PAINT MONO (-4151 2375);
FORCEPROP 2 LAST CDS_LIB standard
J 2
(-3900 2375);
DISPLAY INVISIBLE (-3900 2375);
FORCEPROP 1 LAST OFFPAGE TRUE
J 2
(-4225 2250);
DISPLAY 0.872340 (-4225 2250);
PAINT GREEN (-4225 2250);
DISPLAY INVISIBLE (-4225 2250);
FORCEPROP 1 LAST COMMENT_BODY TRUE
J 2
(-3875 2275);
DISPLAY 0.872340 (-3875 2275);
PAINT PEACH (-3875 2275);
DISPLAY INVISIBLE (-3875 2275);
FORCEPROP 2 LAST PATH I114
J 0
(-4150 2425);
DISPLAY 0.680851 (-4150 2425);
DISPLAY INVISIBLE (-4150 2425);
FORCEADD OFFPAGE..4
R 2
(-3900 2625);
FORCEPROP 2 LAST $XR0 29 
J 0
(-4151 2625);
DISPLAY 0.638298 (-4151 2625);
PAINT MONO (-4151 2625);
FORCEPROP 2 LAST CDS_LIB standard
J 2
(-3900 2625);
DISPLAY INVISIBLE (-3900 2625);
FORCEPROP 2 LAST PATH I115
J 0
(-4150 2675);
DISPLAY 0.680851 (-4150 2675);
DISPLAY INVISIBLE (-4150 2675);
FORCEPROP 1 LAST COMMENT_BODY TRUE
J 2
(-3875 2525);
DISPLAY 0.872340 (-3875 2525);
PAINT PEACH (-3875 2525);
DISPLAY INVISIBLE (-3875 2525);
FORCEPROP 1 LAST OFFPAGE TRUE
J 2
(-4225 2500);
DISPLAY 0.872340 (-4225 2500);
PAINT GREEN (-4225 2500);
DISPLAY INVISIBLE (-4225 2500);
FORCEADD OFFPAGE..1
R 2
(475 3950);
FORCEPROP 2 LAST $XR0 29 
J 0
(661 3950);
DISPLAY 0.638298 (661 3950);
PAINT MONO (661 3950);
FORCEPROP 2 LAST PATH I116
J 0
(675 4000);
DISPLAY 0.680851 (675 4000);
DISPLAY INVISIBLE (675 4000);
FORCEPROP 1 LAST COMMENT_BODY TRUE
J 2
(350 3850);
DISPLAY 0.872340 (350 3850);
PAINT PEACH (350 3850);
DISPLAY INVISIBLE (350 3850);
FORCEPROP 1 LAST OFFPAGE TRUE
J 2
(150 3825);
DISPLAY 0.872340 (150 3825);
PAINT GREEN (150 3825);
DISPLAY INVISIBLE (150 3825);
FORCEPROP 2 LAST CDS_LIB standard
J 2
(475 3950);
DISPLAY INVISIBLE (475 3950);
FORCEADD OFFPAGE..1
R 2
(475 3700);
FORCEPROP 2 LAST $XR0 29 
J 0
(661 3700);
DISPLAY 0.638298 (661 3700);
PAINT MONO (661 3700);
FORCEPROP 2 LAST PATH I119
J 0
(675 3750);
DISPLAY 0.680851 (675 3750);
DISPLAY INVISIBLE (675 3750);
FORCEPROP 1 LAST COMMENT_BODY TRUE
J 2
(350 3600);
DISPLAY 0.872340 (350 3600);
PAINT PEACH (350 3600);
DISPLAY INVISIBLE (350 3600);
FORCEPROP 1 LAST OFFPAGE TRUE
J 2
(150 3575);
DISPLAY 0.872340 (150 3575);
PAINT GREEN (150 3575);
DISPLAY INVISIBLE (150 3575);
FORCEPROP 2 LAST CDS_LIB standard
J 2
(475 3700);
DISPLAY INVISIBLE (475 3700);
FORCEADD Q_RES..1
R 2
(-775 4250);
FORCEPROP 1 LAST PACK_TYPE 0402LF
J 2
(-975 4150);
DISPLAY 0.510638 (-975 4150);
PAINT SKYBLUE (-975 4150);
FORCEPROP 1 LAST MATERIAL CHIP
J 2
(-775 4150);
DISPLAY 0.510638 (-775 4150);
PAINT SKYBLUE (-775 4150);
FORCEPROP 1 LAST TOLERANCE 5%
J 2
(-775 4200);
DISPLAY 0.510638 (-775 4200);
PAINT SKYBLUE (-775 4200);
FORCEPROP 1 LAST VALUE 0
J 0
(-750 4200);
DISPLAY 0.510638 (-750 4200);
PAINT SKYBLUE (-750 4200);
FORCEPROP 1 LAST PART_NUMBER CS00002JB13
J 2
(-725 4350);
DISPLAY 0.510638 (-725 4350);
PAINT WHITE (-725 4350);
FORCEPROP 1 LAST WATTAGE 1/16W
J 0
(-750 4150);
DISPLAY 0.510638 (-750 4150);
PAINT SKYBLUE (-750 4150);
FORCEPROP 1 LAST PATH I122
J 2
(-725 4400);
DISPLAY 0.978723 (-725 4400);
PAINT WHITE (-725 4400);
DISPLAY INVISIBLE (-725 4400);
FORCEPROP 2 LAST CDS_LIB pure_quanta
J 2
(-775 4250);
DISPLAY INVISIBLE (-775 4250);
FORCEPROP 1 LAST LOCATION R673
J 2
(-725 4300);
DISPLAY 0.702128 (-725 4300);
PAINT YELLOW (-725 4300);
FORCEPROP 0 LAST $SEC 1
J 2
(-725 4375);
DISPLAY 0.680851 (-725 4375);
PAINT MONO (-725 4375);
DISPLAY INVISIBLE (-725 4375);
FORCEPROP 0 LAST CDS_SEC 1
J 2
(-725 4375);
DISPLAY 1.021277 (-725 4375);
DISPLAY INVISIBLE (-725 4375);
FORCEPROP 1 LASTPIN (-675 4250) $PN 1
J 2
(-687 4262);
DISPLAY 0.808511 (-687 4262);
PAINT WHITE (-687 4262);
DISPLAY INVISIBLE (-687 4262);
FORCEPROP 1 LASTPIN (-875 4250) $PN 2
J 2
(-837 4262);
DISPLAY 0.808511 (-837 4262);
PAINT WHITE (-837 4262);
DISPLAY INVISIBLE (-837 4262);
FORCEADD Q_INDUCTOR4P_12..1
R 2
(-850 3825);
FORCEPROP 1 LAST MATERIAL EMPTY
J 2
(-626 3635);
DISPLAY 0.510638 (-626 3635);
PAINT RED (-626 3635);
FORCEPROP 2 LAST VALUE 67/320MA
J 2
(-1025 3625);
DISPLAY 0.510638 (-1025 3625);
PAINT SKYBLUE (-1025 3625);
FORCEPROP 2 LAST CURRENT_AMP 320MA
J 2
(-1025 3525);
DISPLAY 0.680851 (-1025 3525);
FORCEPROP 2 LAST PART_TYPE SMLF
J 2
(-1025 3575);
DISPLAY 0.510638 (-1025 3575);
PAINT SKYBLUE (-1025 3575);
FORCEPROP 1 LAST PART_NUMBER CX21SN67000
J 2
(-626 3587);
DISPLAY 0.510638 (-626 3587);
PAINT WHITE (-626 3587);
FORCEPROP 1 LAST PATH I123
J 2
(-850 3825);
DISPLAY 0.723404 (-850 3825);
PAINT GREEN (-850 3825);
DISPLAY INVISIBLE (-850 3825);
FORCEPROP 2 LAST CDS_LIB pure_quanta
J 2
(-850 3825);
DISPLAY INVISIBLE (-850 3825);
FORCEPROP 1 LAST CDS_LMAN_SYM_OUTLINE -250,175,250,-175
J 2
(-850 3825);
DISPLAY 0.468085 (-850 3825);
PAINT GREEN (-850 3825);
DISPLAY INVISIBLE (-850 3825);
FORCEPROP 1 LAST NEEDS_NO_SIZE TRUE
J 2
(-1100 3650);
DISPLAY 0.468085 (-1100 3650);
PAINT GREEN (-1100 3650);
DISPLAY INVISIBLE (-1100 3650);
FORCEPROP 1 LAST LOCATION L21
J 2
(-626 4080);
DISPLAY 0.702128 (-626 4080);
PAINT YELLOW (-626 4080);
FORCEPROP 0 LASTPIN (-450 3950) $PN 1
J 0
(-440 3960);
DISPLAY 0.680851 (-440 3960);
PAINT MONO (-440 3960);
FORCEPROP 0 LASTPIN (-1250 3950) $PN 2
J 2
(-1260 3960);
DISPLAY 0.680851 (-1260 3960);
PAINT MONO (-1260 3960);
FORCEPROP 0 LASTPIN (-1250 3700) $PN 3
J 2
(-1260 3710);
DISPLAY 0.680851 (-1260 3710);
PAINT MONO (-1260 3710);
FORCEPROP 0 LASTPIN (-450 3700) $PN 4
J 0
(-440 3710);
DISPLAY 0.680851 (-440 3710);
PAINT MONO (-440 3710);
FORCEPROP 0 LAST $SEC 1
J 2
(-650 4125);
DISPLAY 0.680851 (-650 4125);
PAINT MONO (-650 4125);
DISPLAY INVISIBLE (-650 4125);
FORCEPROP 0 LAST CDS_SEC 1
J 2
(-650 4125);
DISPLAY 1.021277 (-650 4125);
DISPLAY INVISIBLE (-650 4125);
FORCEADD Q_RES..1
R 2
(-775 3400);
FORCEPROP 1 LAST PART_NUMBER CS00002JB13
J 2
(-725 3500);
DISPLAY 0.510638 (-725 3500);
PAINT WHITE (-725 3500);
FORCEPROP 1 LAST MATERIAL CHIP
J 2
(-775 3300);
DISPLAY 0.510638 (-775 3300);
PAINT SKYBLUE (-775 3300);
FORCEPROP 1 LAST WATTAGE 1/16W
J 0
(-750 3300);
DISPLAY 0.510638 (-750 3300);
PAINT SKYBLUE (-750 3300);
FORCEPROP 1 LAST VALUE 0
J 0
(-750 3350);
DISPLAY 0.510638 (-750 3350);
PAINT SKYBLUE (-750 3350);
FORCEPROP 1 LAST TOLERANCE 5%
J 2
(-775 3350);
DISPLAY 0.510638 (-775 3350);
PAINT SKYBLUE (-775 3350);
FORCEPROP 1 LAST PACK_TYPE 0402LF
J 2
(-975 3300);
DISPLAY 0.510638 (-975 3300);
PAINT SKYBLUE (-975 3300);
FORCEPROP 1 LAST PATH I124
J 2
(-725 3550);
DISPLAY 0.978723 (-725 3550);
PAINT WHITE (-725 3550);
DISPLAY INVISIBLE (-725 3550);
FORCEPROP 2 LAST CDS_LIB pure_quanta
J 2
(-775 3400);
DISPLAY INVISIBLE (-775 3400);
FORCEPROP 1 LAST LOCATION R666
J 2
(-725 3450);
DISPLAY 0.702128 (-725 3450);
PAINT YELLOW (-725 3450);
FORCEPROP 0 LAST $SEC 1
J 2
(-725 3525);
DISPLAY 0.680851 (-725 3525);
PAINT MONO (-725 3525);
DISPLAY INVISIBLE (-725 3525);
FORCEPROP 0 LAST CDS_SEC 1
J 2
(-725 3525);
DISPLAY 1.021277 (-725 3525);
DISPLAY INVISIBLE (-725 3525);
FORCEPROP 1 LASTPIN (-675 3400) $PN 1
J 2
(-687 3412);
DISPLAY 0.808511 (-687 3412);
PAINT WHITE (-687 3412);
DISPLAY INVISIBLE (-687 3412);
FORCEPROP 1 LASTPIN (-875 3400) $PN 2
J 2
(-837 3412);
DISPLAY 0.808511 (-837 3412);
PAINT WHITE (-837 3412);
DISPLAY INVISIBLE (-837 3412);
FORCEADD OFFPAGE..2
R 2
(-3925 3950);
FORCEPROP 2 LAST $XR0 29 
J 0
(-4149 3950);
DISPLAY 0.638298 (-4149 3950);
PAINT MONO (-4149 3950);
FORCEPROP 2 LAST CDS_LIB standard
J 2
(-3925 3950);
DISPLAY INVISIBLE (-3925 3950);
FORCEPROP 1 LAST OFFPAGE TRUE
J 2
(-4250 3825);
DISPLAY 0.872340 (-4250 3825);
PAINT GREEN (-4250 3825);
DISPLAY INVISIBLE (-4250 3825);
FORCEPROP 1 LAST COMMENT_BODY TRUE
J 2
(-3880 3855);
DISPLAY 0.872340 (-3880 3855);
PAINT PEACH (-3880 3855);
DISPLAY INVISIBLE (-3880 3855);
FORCEPROP 2 LAST PATH I125
J 0
(-4125 4000);
DISPLAY 0.680851 (-4125 4000);
DISPLAY INVISIBLE (-4125 4000);
FORCEADD OFFPAGE..2
R 2
(-3925 3700);
FORCEPROP 2 LAST $XR0 29 
J 0
(-4149 3700);
DISPLAY 0.638298 (-4149 3700);
PAINT MONO (-4149 3700);
FORCEPROP 2 LAST CDS_LIB standard
J 2
(-3925 3700);
DISPLAY INVISIBLE (-3925 3700);
FORCEPROP 1 LAST OFFPAGE TRUE
J 2
(-4250 3575);
DISPLAY 0.872340 (-4250 3575);
PAINT GREEN (-4250 3575);
DISPLAY INVISIBLE (-4250 3575);
FORCEPROP 1 LAST COMMENT_BODY TRUE
J 2
(-3880 3605);
DISPLAY 0.872340 (-3880 3605);
PAINT PEACH (-3880 3605);
DISPLAY INVISIBLE (-3880 3605);
FORCEPROP 2 LAST PATH I126
J 0
(-4125 3750);
DISPLAY 0.680851 (-4125 3750);
DISPLAY INVISIBLE (-4125 3750);
FORCEADD OFFPAGE..6
R 2
(2125 -775);
FORCEPROP 2 LAST $XR0 28 
J 0
(2339 -775);
DISPLAY 0.638298 (2339 -775);
PAINT MONO (2339 -775);
FORCEPROP 2 LAST PATH I127
J 0
(2350 -725);
DISPLAY 0.680851 (2350 -725);
DISPLAY INVISIBLE (2350 -725);
FORCEPROP 1 LAST COMMENT_BODY TRUE
J 2
(2025 -850);
DISPLAY 0.872340 (2025 -850);
PAINT GREEN (2025 -850);
DISPLAY INVISIBLE (2025 -850);
FORCEPROP 1 LAST OFFPAGE TRUE
J 2
(1800 -900);
DISPLAY 0.872340 (1800 -900);
DISPLAY INVISIBLE (1800 -900);
FORCEPROP 2 LAST CDS_LIB standard
J 2
(2125 -775);
PAINT MONO (2125 -775);
DISPLAY INVISIBLE (2125 -775);
FORCEADD OFFPAGE..1
R 2
(2125 -825);
FORCEPROP 2 LAST $XR0 28 
J 0
(2311 -825);
DISPLAY 0.638298 (2311 -825);
PAINT MONO (2311 -825);
FORCEPROP 2 LAST PATH I128
J 0
(2350 -775);
DISPLAY 0.680851 (2350 -775);
DISPLAY INVISIBLE (2350 -775);
FORCEPROP 1 LAST COMMENT_BODY TRUE
J 2
(2000 -925);
DISPLAY 0.872340 (2000 -925);
PAINT GREEN (2000 -925);
DISPLAY INVISIBLE (2000 -925);
FORCEPROP 1 LAST OFFPAGE TRUE
J 2
(1800 -950);
DISPLAY 0.872340 (1800 -950);
DISPLAY INVISIBLE (1800 -950);
FORCEPROP 2 LAST CDS_LIB standard
J 2
(2125 -825);
PAINT MONO (2125 -825);
DISPLAY INVISIBLE (2125 -825);
FORCEADD OFFPAGE..1
R 2
(325 -725);
FORCEPROP 2 LAST $XR0 29 
J 0
(511 -725);
DISPLAY 0.638298 (511 -725);
PAINT MONO (511 -725);
FORCEPROP 2 LAST PATH I133
J 0
(525 -675);
DISPLAY 0.680851 (525 -675);
DISPLAY INVISIBLE (525 -675);
FORCEPROP 1 LAST COMMENT_BODY TRUE
J 2
(200 -825);
DISPLAY 0.872340 (200 -825);
PAINT GREEN (200 -825);
DISPLAY INVISIBLE (200 -825);
FORCEPROP 1 LAST OFFPAGE TRUE
J 2
(0 -850);
DISPLAY 0.872340 (0 -850);
DISPLAY INVISIBLE (0 -850);
FORCEPROP 2 LAST CDS_LIB standard
J 2
(325 -725);
PAINT MONO (325 -725);
DISPLAY INVISIBLE (325 -725);
FORCEADD OFFPAGE..5
R 2
(325 -675);
FORCEPROP 2 LAST $XR0 29 
J 0
(514 -675);
DISPLAY 0.638298 (514 -675);
PAINT MONO (514 -675);
FORCEPROP 2 LAST CDS_LIB standard
J 2
(325 -675);
PAINT MONO (325 -675);
DISPLAY INVISIBLE (325 -675);
FORCEPROP 1 LAST OFFPAGE TRUE
J 2
(0 -800);
DISPLAY 0.872340 (0 -800);
PAINT GREEN (0 -800);
DISPLAY INVISIBLE (0 -800);
FORCEPROP 1 LAST COMMENT_BODY TRUE
J 2
(225 -750);
DISPLAY 0.872340 (225 -750);
PAINT PEACH (225 -750);
DISPLAY INVISIBLE (225 -750);
FORCEPROP 2 LAST PATH I134
J 0
(525 -625);
DISPLAY 0.680851 (525 -625);
DISPLAY INVISIBLE (525 -625);
FORCEADD Q_RES..1
R 2
(350 -775);
FORCEPROP 1 LAST MATERIAL CHIP
J 2
(625 -800);
DISPLAY 0.510638 (625 -800);
PAINT SKYBLUE (625 -800);
FORCEPROP 1 LAST TOLERANCE 5%
J 2
(500 -800);
DISPLAY 0.510638 (500 -800);
PAINT SKYBLUE (500 -800);
FORCEPROP 1 LAST WATTAGE 1/16W
J 0
(650 -800);
DISPLAY 0.510638 (650 -800);
PAINT SKYBLUE (650 -800);
FORCEPROP 1 LAST PACK_TYPE 0402LF
J 2
(950 -800);
DISPLAY 0.510638 (950 -800);
PAINT SKYBLUE (950 -800);
FORCEPROP 1 LAST VALUE 0
J 0
(400 -800);
DISPLAY 0.510638 (400 -800);
PAINT SKYBLUE (400 -800);
FORCEPROP 1 LAST PART_NUMBER CS00002JB13
J 2
(600 -750);
DISPLAY 0.510638 (600 -750);
PAINT WHITE (600 -750);
DISPLAY INVISIBLE (600 -750);
FORCEPROP 1 LAST PATH I135
J 2
(400 -625);
DISPLAY 0.978723 (400 -625);
PAINT WHITE (400 -625);
DISPLAY INVISIBLE (400 -625);
FORCEPROP 2 LAST CDS_LIB pure_quanta
J 0
(350 -775);
DISPLAY INVISIBLE (350 -775);
FORCEPROP 1 LAST LOCATION R731
J 2
(300 -775);
DISPLAY 0.702128 (300 -775);
PAINT YELLOW (300 -775);
FORCEPROP 0 LAST $SEC 1
J 0
(300 -725);
DISPLAY 0.680851 (300 -725);
PAINT MONO (300 -725);
DISPLAY INVISIBLE (300 -725);
FORCEPROP 0 LAST CDS_SEC 1
J 0
(300 -725);
DISPLAY 1.021277 (300 -725);
DISPLAY INVISIBLE (300 -725);
FORCEPROP 1 LASTPIN (450 -775) $PN 1
J 2
(438 -763);
DISPLAY 0.808511 (438 -763);
PAINT WHITE (438 -763);
DISPLAY INVISIBLE (438 -763);
FORCEPROP 1 LASTPIN (250 -775) $PN 2
J 2
(288 -763);
DISPLAY 0.808511 (288 -763);
PAINT WHITE (288 -763);
DISPLAY INVISIBLE (288 -763);
FORCEADD Q_RES..1
R 2
(350 -825);
FORCEPROP 1 LAST TOLERANCE 5%
J 2
(500 -850);
DISPLAY 0.510638 (500 -850);
PAINT SKYBLUE (500 -850);
FORCEPROP 1 LAST PACK_TYPE 0402LF
J 2
(950 -850);
DISPLAY 0.510638 (950 -850);
PAINT SKYBLUE (950 -850);
FORCEPROP 1 LAST MATERIAL CHIP
J 2
(625 -850);
DISPLAY 0.510638 (625 -850);
PAINT SKYBLUE (625 -850);
FORCEPROP 1 LAST VALUE 0
J 0
(400 -850);
DISPLAY 0.510638 (400 -850);
PAINT SKYBLUE (400 -850);
FORCEPROP 1 LAST WATTAGE 1/16W
J 0
(650 -850);
DISPLAY 0.510638 (650 -850);
PAINT SKYBLUE (650 -850);
FORCEPROP 1 LAST PART_NUMBER CS00002JB13
J 2
(600 -800);
DISPLAY 0.510638 (600 -800);
PAINT WHITE (600 -800);
DISPLAY INVISIBLE (600 -800);
FORCEPROP 1 LAST PATH I136
J 2
(400 -675);
DISPLAY 0.978723 (400 -675);
PAINT WHITE (400 -675);
DISPLAY INVISIBLE (400 -675);
FORCEPROP 2 LAST CDS_LIB pure_quanta
J 0
(350 -825);
DISPLAY INVISIBLE (350 -825);
FORCEPROP 1 LAST LOCATION R732
J 2
(300 -825);
DISPLAY 0.702128 (300 -825);
PAINT YELLOW (300 -825);
FORCEPROP 0 LAST $SEC 1
J 0
(300 -775);
DISPLAY 0.680851 (300 -775);
PAINT MONO (300 -775);
DISPLAY INVISIBLE (300 -775);
FORCEPROP 0 LAST CDS_SEC 1
J 0
(300 -775);
DISPLAY 1.021277 (300 -775);
DISPLAY INVISIBLE (300 -775);
FORCEPROP 1 LASTPIN (450 -825) $PN 1
J 2
(438 -813);
DISPLAY 0.808511 (438 -813);
PAINT WHITE (438 -813);
DISPLAY INVISIBLE (438 -813);
FORCEPROP 1 LASTPIN (250 -825) $PN 2
J 2
(288 -813);
DISPLAY 0.808511 (288 -813);
PAINT WHITE (288 -813);
DISPLAY INVISIBLE (288 -813);
FORCEADD OFFPAGE..1
R 2
(1125 225);
FORCEPROP 2 LAST $XR0 10 
J 0
(1311 225);
DISPLAY 0.638298 (1311 225);
PAINT MONO (1311 225);
FORCEPROP 2 LAST CDS_LIB standard
J 2
(1125 225);
DISPLAY INVISIBLE (1125 225);
FORCEPROP 1 LAST OFFPAGE TRUE
J 2
(800 100);
DISPLAY 0.872340 (800 100);
PAINT GREEN (800 100);
DISPLAY INVISIBLE (800 100);
FORCEPROP 1 LAST COMMENT_BODY TRUE
J 2
(1000 125);
DISPLAY 0.872340 (1000 125);
PAINT PEACH (1000 125);
DISPLAY INVISIBLE (1000 125);
FORCEPROP 2 LAST PATH I137
J 0
(1325 275);
DISPLAY 0.680851 (1325 275);
DISPLAY INVISIBLE (1325 275);
FORCEADD OFFPAGE..1
R 2
(1125 50);
FORCEPROP 2 LAST $XR0 10 
J 0
(1311 50);
DISPLAY 0.638298 (1311 50);
PAINT MONO (1311 50);
FORCEPROP 2 LAST PATH I138
J 0
(1325 100);
DISPLAY 0.680851 (1325 100);
DISPLAY INVISIBLE (1325 100);
FORCEPROP 1 LAST COMMENT_BODY TRUE
J 2
(1000 -50);
DISPLAY 0.872340 (1000 -50);
PAINT PEACH (1000 -50);
DISPLAY INVISIBLE (1000 -50);
FORCEPROP 1 LAST OFFPAGE TRUE
J 2
(800 -75);
DISPLAY 0.872340 (800 -75);
PAINT GREEN (800 -75);
DISPLAY INVISIBLE (800 -75);
FORCEPROP 2 LAST CDS_LIB standard
J 2
(1125 50);
DISPLAY INVISIBLE (1125 50);
FORCEADD Q_RES..1
(-50 500);
FORCEPROP 1 LAST VALUE 0
J 2
(-75 450);
DISPLAY 0.510638 (-75 450);
PAINT SKYBLUE (-75 450);
FORCEPROP 1 LAST MATERIAL CHIP
J 0
(-50 400);
DISPLAY 0.510638 (-50 400);
PAINT SKYBLUE (-50 400);
FORCEPROP 1 LAST PACK_TYPE 0402LF
J 0
(150 400);
DISPLAY 0.510638 (150 400);
PAINT SKYBLUE (150 400);
FORCEPROP 1 LAST WATTAGE 1/16W
J 2
(-75 400);
DISPLAY 0.510638 (-75 400);
PAINT SKYBLUE (-75 400);
FORCEPROP 1 LAST TOLERANCE 5%
J 0
(-50 450);
DISPLAY 0.510638 (-50 450);
PAINT SKYBLUE (-50 450);
FORCEPROP 1 LAST PART_NUMBER CS00002JB13
J 0
(-150 525);
DISPLAY 0.510638 (-150 525);
PAINT WHITE (-150 525);
FORCEPROP 1 LAST PATH I141
J 0
(-100 650);
DISPLAY 0.978723 (-100 650);
PAINT WHITE (-100 650);
DISPLAY INVISIBLE (-100 650);
FORCEPROP 2 LAST CDS_LIB pure_quanta
J 0
(-50 500);
DISPLAY INVISIBLE (-50 500);
FORCEPROP 1 LAST LOCATION R671
J 0
(-100 550);
DISPLAY 0.702128 (-100 550);
PAINT YELLOW (-100 550);
FORCEPROP 0 LAST $SEC 1
J 0
(-100 625);
DISPLAY 0.680851 (-100 625);
PAINT MONO (-100 625);
DISPLAY INVISIBLE (-100 625);
FORCEPROP 0 LAST CDS_SEC 1
J 0
(-100 625);
DISPLAY 1.021277 (-100 625);
DISPLAY INVISIBLE (-100 625);
FORCEPROP 1 LASTPIN (-150 500) $PN 1
J 0
(-138 512);
DISPLAY 0.808511 (-138 512);
PAINT WHITE (-138 512);
DISPLAY INVISIBLE (-138 512);
FORCEPROP 1 LASTPIN (50 500) $PN 2
J 0
(12 512);
DISPLAY 0.808511 (12 512);
PAINT WHITE (12 512);
DISPLAY INVISIBLE (12 512);
FORCEADD Q_CAP..2
R 2
(-50 225);
FORCEPROP 1 LAST PACK_TYPE 0402
J 1
(-250 150);
DISPLAY 0.510638 (-250 150);
PAINT SKYBLUE (-250 150);
FORCEPROP 1 LAST MATERIAL EMPTY
J 2
(250 150);
DISPLAY 0.510638 (250 150);
PAINT SKYBLUE (250 150);
FORCEPROP 1 LAST VALUE 0.1UF
J 0
(75 175);
DISPLAY 0.510638 (75 175);
PAINT SKYBLUE (75 175);
FORCEPROP 1 LAST VOLTAGE 25V
J 2
(50 175);
DISPLAY 0.510638 (50 175);
PAINT SKYBLUE (50 175);
FORCEPROP 1 LAST TOLERANCE 10%
J 0
(-175 175);
DISPLAY 0.510638 (-175 175);
PAINT SKYBLUE (-175 175);
FORCEPROP 1 LAST PART_NUMBER CH4104K1B00
J 1
(-50 275);
DISPLAY 0.510638 (-50 275);
PAINT WHITE (-50 275);
FORCEPROP 1 LAST PATH I142
J 2
(-50 425);
DISPLAY 0.978723 (-50 425);
PAINT WHITE (-50 425);
DISPLAY INVISIBLE (-50 425);
FORCEPROP 2 LAST CDS_LIB pure_quanta
J 2
(-50 225);
DISPLAY INVISIBLE (-50 225);
FORCEPROP 1 LAST LOCATION C238
J 1
(-50 325);
DISPLAY 0.702128 (-50 325);
PAINT YELLOW (-50 325);
FORCEPROP 0 LAST $SEC 1
J 2
(-50 375);
DISPLAY 0.680851 (-50 375);
PAINT MONO (-50 375);
DISPLAY INVISIBLE (-50 375);
FORCEPROP 0 LAST CDS_SEC 1
J 2
(-50 375);
DISPLAY 1.021277 (-50 375);
DISPLAY INVISIBLE (-50 375);
FORCEPROP 1 LASTPIN (50 225) $PN 1
J 2
(60 240);
DISPLAY 0.808511 (60 240);
PAINT WHITE (60 240);
DISPLAY INVISIBLE (60 240);
FORCEPROP 1 LASTPIN (-150 225) $PN 2
J 2
(-135 240);
DISPLAY 0.808511 (-135 240);
PAINT WHITE (-135 240);
DISPLAY INVISIBLE (-135 240);
FORCEADD Q_CAP..2
R 2
(-50 50);
FORCEPROP 1 LAST PART_NUMBER CH4104K1B00
J 1
(-50 100);
DISPLAY 0.510638 (-50 100);
PAINT WHITE (-50 100);
FORCEPROP 1 LAST TOLERANCE 10%
J 0
(-175 0);
DISPLAY 0.510638 (-175 0);
PAINT SKYBLUE (-175 0);
FORCEPROP 1 LAST PACK_TYPE 0402
J 1
(-225 -50);
DISPLAY 0.510638 (-225 -50);
PAINT SKYBLUE (-225 -50);
FORCEPROP 1 LAST VALUE 0.1UF
J 0
(75 0);
DISPLAY 0.510638 (75 0);
PAINT SKYBLUE (75 0);
FORCEPROP 1 LAST VOLTAGE 25V
J 2
(50 0);
DISPLAY 0.510638 (50 0);
PAINT SKYBLUE (50 0);
FORCEPROP 1 LAST MATERIAL EMPTY
J 2
(225 -50);
DISPLAY 0.510638 (225 -50);
PAINT SKYBLUE (225 -50);
FORCEPROP 1 LAST PATH I143
J 2
(-50 250);
DISPLAY 0.978723 (-50 250);
PAINT WHITE (-50 250);
DISPLAY INVISIBLE (-50 250);
FORCEPROP 2 LAST CDS_LIB pure_quanta
J 2
(-50 50);
DISPLAY INVISIBLE (-50 50);
FORCEPROP 1 LAST LOCATION C239
J 1
(-50 125);
DISPLAY 0.702128 (-50 125);
PAINT YELLOW (-50 125);
FORCEPROP 0 LAST $SEC 1
J 2
(-50 200);
DISPLAY 0.680851 (-50 200);
PAINT MONO (-50 200);
DISPLAY INVISIBLE (-50 200);
FORCEPROP 0 LAST CDS_SEC 1
J 2
(-50 200);
DISPLAY 1.021277 (-50 200);
DISPLAY INVISIBLE (-50 200);
FORCEPROP 1 LASTPIN (50 50) $PN 1
J 2
(60 65);
DISPLAY 0.808511 (60 65);
PAINT WHITE (60 65);
DISPLAY INVISIBLE (60 65);
FORCEPROP 1 LASTPIN (-150 50) $PN 2
J 2
(-135 65);
DISPLAY 0.808511 (-135 65);
PAINT WHITE (-135 65);
DISPLAY INVISIBLE (-135 65);
FORCEADD Q_RES..1
(-50 -125);
FORCEPROP 1 LAST PACK_TYPE 0402LF
J 0
(150 -225);
DISPLAY 0.510638 (150 -225);
PAINT SKYBLUE (150 -225);
FORCEPROP 1 LAST PART_NUMBER CS00002JB13
J 0
(-150 -100);
DISPLAY 0.510638 (-150 -100);
PAINT WHITE (-150 -100);
FORCEPROP 1 LAST MATERIAL CHIP
J 0
(-50 -225);
DISPLAY 0.510638 (-50 -225);
PAINT SKYBLUE (-50 -225);
FORCEPROP 1 LAST TOLERANCE 5%
J 0
(-50 -175);
DISPLAY 0.510638 (-50 -175);
PAINT SKYBLUE (-50 -175);
FORCEPROP 1 LAST VALUE 0
J 2
(-75 -175);
DISPLAY 0.510638 (-75 -175);
PAINT SKYBLUE (-75 -175);
FORCEPROP 1 LAST WATTAGE 1/16W
J 2
(-75 -225);
DISPLAY 0.510638 (-75 -225);
PAINT SKYBLUE (-75 -225);
FORCEPROP 1 LAST PATH I144
J 0
(-100 25);
DISPLAY 0.978723 (-100 25);
PAINT WHITE (-100 25);
DISPLAY INVISIBLE (-100 25);
FORCEPROP 2 LAST CDS_LIB pure_quanta
J 0
(-50 -125);
DISPLAY INVISIBLE (-50 -125);
FORCEPROP 1 LAST LOCATION R672
J 0
(-100 -75);
DISPLAY 0.702128 (-100 -75);
PAINT YELLOW (-100 -75);
FORCEPROP 0 LAST $SEC 1
J 0
(-100 0);
DISPLAY 0.680851 (-100 0);
PAINT MONO (-100 0);
DISPLAY INVISIBLE (-100 0);
FORCEPROP 0 LAST CDS_SEC 1
J 0
(-100 0);
DISPLAY 1.021277 (-100 0);
DISPLAY INVISIBLE (-100 0);
FORCEPROP 1 LASTPIN (-150 -125) $PN 1
J 0
(-138 -113);
DISPLAY 0.808511 (-138 -113);
PAINT WHITE (-138 -113);
DISPLAY INVISIBLE (-138 -113);
FORCEPROP 1 LASTPIN (50 -125) $PN 2
J 0
(12 -113);
DISPLAY 0.808511 (12 -113);
PAINT WHITE (12 -113);
DISPLAY INVISIBLE (12 -113);
FORCEADD VCCAUX15..1
(-2150 575);
FORCEPROP 3 LASTPIN (-2150 525) SIG_NAME P3V3_AUX\g
J 0
(-2140 535);
DISPLAY 0.659574 (-2140 535);
PAINT MONO (-2140 535);
DISPLAY INVISIBLE (-2140 535);
FORCEPROP 1 LAST HDL_POWER P3V3_AUX
J 1
(-2150 625);
DISPLAY 0.702128 (-2150 625);
PAINT GREEN (-2150 625);
FORCEPROP 2 LAST CDS_LIB logical_power
J 0
(-2150 575);
DISPLAY INVISIBLE (-2150 575);
FORCEPROP 1 LAST PATH I145
J 0
(-2100 600);
DISPLAY 0.872340 (-2100 600);
PAINT AQUA (-2100 600);
DISPLAY INVISIBLE (-2100 600);
FORCEADD Q_CAP..1
R 2
(-2425 300);
FORCEPROP 1 LAST TOLERANCE 10%
J 2
(-2475 250);
DISPLAY 0.978723 (-2475 250);
FORCEPROP 1 LAST MATERIAL X7R
J 2
(-2475 200);
DISPLAY 0.978723 (-2475 200);
FORCEPROP 1 LAST VOLTAGE 25V
J 2
(-2475 300);
DISPLAY 0.978723 (-2475 300);
FORCEPROP 1 LAST VALUE 0.1UF
J 2
(-2475 350);
DISPLAY 0.978723 (-2475 350);
FORCEPROP 1 LAST PART_NUMBER CH4104K1B00
J 2
(-2475 150);
DISPLAY 0.978723 (-2475 150);
FORCEPROP 1 LAST PACK_TYPE 0402
J 2
(-2475 100);
DISPLAY 0.978723 (-2475 100);
FORCEPROP 2 LAST CDS_LIB pure_quanta
J 2
(-2425 300);
DISPLAY INVISIBLE (-2425 300);
FORCEPROP 1 LAST PATH I146
J 2
(-2475 450);
DISPLAY 0.978723 (-2475 450);
PAINT WHITE (-2475 450);
DISPLAY INVISIBLE (-2475 450);
FORCEPROP 1 LAST LOCATION C237
J 2
(-2475 400);
DISPLAY 0.978723 (-2475 400);
FORCEPROP 1 LASTPIN (-2425 400) $PN 1
J 2
(-2435 380);
DISPLAY 0.787234 (-2435 380);
PAINT MONO (-2435 380);
FORCEPROP 1 LASTPIN (-2425 200) $PN 2
J 2
(-2435 180);
DISPLAY 0.787234 (-2435 180);
PAINT MONO (-2435 180);
FORCEPROP 2 LAST $SEC 1
J 0
(-2475 500);
DISPLAY 0.680851 (-2475 500);
PAINT MONO (-2475 500);
DISPLAY INVISIBLE (-2475 500);
FORCEPROP 2 LAST CDS_SEC 1
J 0
(-2475 500);
DISPLAY 1.021277 (-2475 500);
DISPLAY INVISIBLE (-2475 500);
FORCEADD UNIVERSAL_GND..1
(-2425 -75);
FORCEPROP 3 LASTPIN (-2425 -25) SIG_NAME GND\g
J 0
(-2415 -15);
DISPLAY 0.659574 (-2415 -15);
PAINT MONO (-2415 -15);
DISPLAY INVISIBLE (-2415 -15);
FORCEPROP 1 LAST HDL_POWER GND
J 1
(-2400 -150);
DISPLAY 0.702128 (-2400 -150);
PAINT GREEN (-2400 -150);
FORCEPROP 2 LAST CDS_LIB logical_power
J 0
(-2425 -75);
DISPLAY INVISIBLE (-2425 -75);
FORCEPROP 1 LAST PATH I147
J 0
(-2350 -75);
DISPLAY 0.872340 (-2350 -75);
PAINT AQUA (-2350 -75);
DISPLAY INVISIBLE (-2350 -75);
FORCEADD Q_CAP..1
R 2
(-3050 275);
FORCEPROP 1 LAST MATERIAL X7R
J 2
(-3100 175);
DISPLAY 0.978723 (-3100 175);
FORCEPROP 1 LAST VOLTAGE 25V
J 2
(-3100 275);
DISPLAY 0.978723 (-3100 275);
FORCEPROP 1 LAST PACK_TYPE 0402
J 2
(-3100 75);
DISPLAY 0.978723 (-3100 75);
FORCEPROP 1 LAST PART_NUMBER CH4104K1B00
J 2
(-3100 125);
DISPLAY 0.978723 (-3100 125);
FORCEPROP 1 LAST TOLERANCE 10%
J 2
(-3100 225);
DISPLAY 0.978723 (-3100 225);
FORCEPROP 1 LAST VALUE 0.1UF
J 2
(-3100 325);
DISPLAY 0.978723 (-3100 325);
FORCEPROP 2 LAST CDS_LIB pure_quanta
J 2
(-3050 275);
DISPLAY INVISIBLE (-3050 275);
FORCEPROP 1 LAST PATH I148
J 2
(-3100 425);
DISPLAY 0.978723 (-3100 425);
PAINT WHITE (-3100 425);
DISPLAY INVISIBLE (-3100 425);
FORCEPROP 1 LAST LOCATION C236
J 2
(-3100 375);
DISPLAY 0.978723 (-3100 375);
FORCEPROP 1 LASTPIN (-3050 375) $PN 1
J 2
(-3060 355);
DISPLAY 0.787234 (-3060 355);
PAINT MONO (-3060 355);
FORCEPROP 1 LASTPIN (-3050 175) $PN 2
J 2
(-3060 155);
DISPLAY 0.787234 (-3060 155);
PAINT MONO (-3060 155);
FORCEPROP 2 LAST $SEC 1
J 0
(-3100 475);
DISPLAY 0.680851 (-3100 475);
PAINT MONO (-3100 475);
DISPLAY INVISIBLE (-3100 475);
FORCEPROP 2 LAST CDS_SEC 1
J 0
(-3100 475);
DISPLAY 1.021277 (-3100 475);
DISPLAY INVISIBLE (-3100 475);
FORCEADD VCCAUX15..1
(-3800 -375);
FORCEPROP 3 LASTPIN (-3800 -425) SIG_NAME P3V3_AUX\g
J 0
(-3790 -415);
DISPLAY 0.659574 (-3790 -415);
PAINT MONO (-3790 -415);
DISPLAY INVISIBLE (-3790 -415);
FORCEPROP 1 LAST HDL_POWER P3V3_AUX
J 1
(-3800 -325);
DISPLAY 0.702128 (-3800 -325);
PAINT GREEN (-3800 -325);
FORCEPROP 2 LAST CDS_LIB logical_power
J 0
(-3800 -375);
DISPLAY INVISIBLE (-3800 -375);
FORCEPROP 1 LAST PATH I149
J 0
(-3750 -350);
DISPLAY 0.872340 (-3750 -350);
PAINT AQUA (-3750 -350);
DISPLAY INVISIBLE (-3750 -350);
FORCEADD Q_CAP..1
R 2
(-3625 275);
FORCEPROP 1 LAST VALUE 0.1UF
J 2
(-3675 325);
DISPLAY 0.978723 (-3675 325);
FORCEPROP 1 LAST VOLTAGE 25V
J 2
(-3675 275);
DISPLAY 0.978723 (-3675 275);
FORCEPROP 1 LAST TOLERANCE 10%
J 2
(-3675 225);
DISPLAY 0.978723 (-3675 225);
FORCEPROP 1 LAST PART_NUMBER CH4104K1B00
J 2
(-3675 125);
DISPLAY 0.978723 (-3675 125);
FORCEPROP 1 LAST MATERIAL X7R
J 2
(-3675 175);
DISPLAY 0.978723 (-3675 175);
FORCEPROP 1 LAST PACK_TYPE 0402
J 2
(-3675 75);
DISPLAY 0.978723 (-3675 75);
FORCEPROP 2 LAST CDS_LIB pure_quanta
J 2
(-3625 275);
DISPLAY INVISIBLE (-3625 275);
FORCEPROP 1 LAST PATH I150
J 2
(-3675 425);
DISPLAY 0.978723 (-3675 425);
PAINT WHITE (-3675 425);
DISPLAY INVISIBLE (-3675 425);
FORCEPROP 1 LAST LOCATION C219
J 2
(-3675 375);
DISPLAY 0.978723 (-3675 375);
FORCEPROP 1 LASTPIN (-3625 375) $PN 1
J 2
(-3635 355);
DISPLAY 0.787234 (-3635 355);
PAINT MONO (-3635 355);
FORCEPROP 1 LASTPIN (-3625 175) $PN 2
J 2
(-3635 155);
DISPLAY 0.787234 (-3635 155);
PAINT MONO (-3635 155);
FORCEPROP 2 LAST $SEC 1
J 0
(-3675 475);
DISPLAY 0.680851 (-3675 475);
PAINT MONO (-3675 475);
DISPLAY INVISIBLE (-3675 475);
FORCEPROP 2 LAST CDS_SEC 1
J 0
(-3675 475);
DISPLAY 1.021277 (-3675 475);
DISPLAY INVISIBLE (-3675 475);
FORCEADD UNIVERSAL_GND..1
(-1100 -1475);
FORCEPROP 3 LASTPIN (-1100 -1425) SIG_NAME GND\g
J 0
(-1090 -1415);
DISPLAY 0.659574 (-1090 -1415);
PAINT MONO (-1090 -1415);
DISPLAY INVISIBLE (-1090 -1415);
FORCEPROP 1 LAST HDL_POWER GND
J 1
(-1075 -1550);
DISPLAY 0.702128 (-1075 -1550);
PAINT GREEN (-1075 -1550);
FORCEPROP 1 LAST PATH I151
J 0
(-1025 -1475);
DISPLAY 0.872340 (-1025 -1475);
PAINT AQUA (-1025 -1475);
DISPLAY INVISIBLE (-1025 -1475);
FORCEPROP 2 LAST CDS_LIB logical_power
J 0
(-1100 -1475);
DISPLAY INVISIBLE (-1100 -1475);
FORCEADD Q_RES..2
(-3800 -725);
FORCEPROP 1 LAST MATERIAL EMPTY
J 0
(-3760 -800);
DISPLAY 0.978723 (-3760 -800);
FORCEPROP 1 LAST TOLERANCE 1%
J 0
(-3755 -700);
DISPLAY 0.978723 (-3755 -700);
FORCEPROP 1 LAST VALUE 10K
J 0
(-3755 -650);
DISPLAY 0.978723 (-3755 -650);
FORCEPROP 1 LAST WATTAGE 1/16W
J 0
(-3760 -750);
DISPLAY 0.978723 (-3760 -750);
FORCEPROP 1 LAST PART_NUMBER CS31002FB08
J 0
(-3760 -850);
DISPLAY 0.978723 (-3760 -850);
FORCEPROP 1 LAST PACK_TYPE 0402LF
J 0
(-3760 -900);
DISPLAY 0.978723 (-3760 -900);
FORCEPROP 1 LAST PATH I153
J 0
(-3750 -550);
DISPLAY 0.978723 (-3750 -550);
PAINT WHITE (-3750 -550);
DISPLAY INVISIBLE (-3750 -550);
FORCEPROP 2 LAST CDS_LIB pure_quanta
J 0
(-3800 -725);
DISPLAY INVISIBLE (-3800 -725);
FORCEPROP 1 LAST LOCATION R712
J 0
(-3755 -600);
DISPLAY 0.978723 (-3755 -600);
FORCEPROP 1 LASTPIN (-3800 -625) $PN 1
J 0
(-3795 -663);
DISPLAY 0.787234 (-3795 -663);
PAINT MONO (-3795 -663);
FORCEPROP 1 LASTPIN (-3800 -825) $PN 2
J 0
(-3795 -815);
DISPLAY 0.787234 (-3795 -815);
PAINT MONO (-3795 -815);
FORCEPROP 0 LAST $SEC 1
J 0
(-3750 -550);
DISPLAY 0.680851 (-3750 -550);
PAINT MONO (-3750 -550);
DISPLAY INVISIBLE (-3750 -550);
FORCEPROP 0 LAST CDS_SEC 1
J 0
(-3750 -550);
DISPLAY 0.680851 (-3750 -550);
DISPLAY INVISIBLE (-3750 -550);
FORCEADD OFFPAGE..1
(-2875 -925);
FORCEPROP 2 LAST $XR0 29 
J 0
(-3096 -925);
DISPLAY 0.638298 (-3096 -925);
PAINT MONO (-3096 -925);
FORCEPROP 2 LAST $XR1 28 
J 0
(-3186 -925);
DISPLAY 0.638298 (-3186 -925);
PAINT MONO (-3186 -925);
FORCEPROP 2 LAST CDS_LIB standard
J 0
(-2875 -925);
DISPLAY INVISIBLE (-2875 -925);
FORCEPROP 1 LAST OFFPAGE TRUE
J 0
(-2550 -1050);
DISPLAY 0.872340 (-2550 -1050);
PAINT GREEN (-2550 -1050);
DISPLAY INVISIBLE (-2550 -1050);
FORCEPROP 1 LAST COMMENT_BODY TRUE
J 0
(-2750 -1025);
DISPLAY 0.872340 (-2750 -1025);
PAINT PEACH (-2750 -1025);
DISPLAY INVISIBLE (-2750 -1025);
FORCEPROP 2 LAST PATH I154
J 0
(-3125 -875);
DISPLAY 0.680851 (-3125 -875);
DISPLAY INVISIBLE (-3125 -875);
FORCEADD Q_RES..2
R 2
(-3600 -1275);
FORCEPROP 1 LAST WATTAGE 1/16W
J 2
(-3640 -1300);
DISPLAY 0.978723 (-3640 -1300);
FORCEPROP 1 LAST VALUE 100
J 2
(-3645 -1200);
DISPLAY 0.978723 (-3645 -1200);
FORCEPROP 1 LAST TOLERANCE 1%
J 2
(-3645 -1250);
DISPLAY 0.978723 (-3645 -1250);
FORCEPROP 1 LAST MATERIAL CHIP
J 2
(-3640 -1350);
DISPLAY 0.978723 (-3640 -1350);
FORCEPROP 1 LAST PART_NUMBER CS11002FB07
J 2
(-3640 -1400);
DISPLAY 0.978723 (-3640 -1400);
FORCEPROP 1 LAST PACK_TYPE 0402LF
J 2
(-3640 -1450);
DISPLAY 0.978723 (-3640 -1450);
FORCEPROP 2 LAST CDS_LIB pure_quanta
J 2
(-3600 -1275);
DISPLAY INVISIBLE (-3600 -1275);
FORCEPROP 1 LAST PATH I155
J 2
(-3650 -1100);
DISPLAY 0.978723 (-3650 -1100);
PAINT WHITE (-3650 -1100);
DISPLAY INVISIBLE (-3650 -1100);
FORCEPROP 1 LAST LOCATION R694
J 2
(-3645 -1150);
DISPLAY 0.978723 (-3645 -1150);
FORCEPROP 1 LASTPIN (-3600 -1175) $PN 1
J 2
(-3605 -1213);
DISPLAY 0.787234 (-3605 -1213);
PAINT MONO (-3605 -1213);
FORCEPROP 1 LASTPIN (-3600 -1375) $PN 2
J 2
(-3605 -1365);
DISPLAY 0.787234 (-3605 -1365);
PAINT MONO (-3605 -1365);
FORCEPROP 0 LAST $SEC 1
J 2
(-3650 -1100);
DISPLAY 0.680851 (-3650 -1100);
PAINT MONO (-3650 -1100);
DISPLAY INVISIBLE (-3650 -1100);
FORCEPROP 0 LAST CDS_SEC 1
J 2
(-3650 -1100);
DISPLAY 0.680851 (-3650 -1100);
DISPLAY INVISIBLE (-3650 -1100);
FORCEADD UNIVERSAL_GND..1
(-3600 -1575);
FORCEPROP 3 LASTPIN (-3600 -1525) SIG_NAME GND\g
J 0
(-3590 -1515);
DISPLAY 0.659574 (-3590 -1515);
PAINT MONO (-3590 -1515);
DISPLAY INVISIBLE (-3590 -1515);
FORCEPROP 1 LAST HDL_POWER GND
J 1
(-3575 -1650);
DISPLAY 0.702128 (-3575 -1650);
PAINT GREEN (-3575 -1650);
FORCEPROP 2 LAST CDS_LIB logical_power
J 0
(-3600 -1575);
DISPLAY INVISIBLE (-3600 -1575);
FORCEPROP 1 LAST PATH I156
J 0
(-3525 -1575);
DISPLAY 0.872340 (-3525 -1575);
PAINT AQUA (-3525 -1575);
DISPLAY INVISIBLE (-3525 -1575);
FORCEADD Q_RES..2
(4225 3800);
FORCEPROP 1 LAST PACK_TYPE 0402LF
J 0
(4265 3625);
DISPLAY 0.978723 (4265 3625);
FORCEPROP 1 LAST PART_NUMBER CS41002FB09
J 0
(4265 3675);
DISPLAY 0.978723 (4265 3675);
FORCEPROP 1 LAST VALUE 100K
J 0
(4270 3875);
DISPLAY 0.978723 (4270 3875);
FORCEPROP 1 LAST TOLERANCE 1%
J 0
(4270 3825);
DISPLAY 0.978723 (4270 3825);
FORCEPROP 1 LAST MATERIAL EMPTY
J 0
(4265 3725);
DISPLAY 0.978723 (4265 3725);
FORCEPROP 1 LAST WATTAGE 1/16W
J 0
(4265 3775);
DISPLAY 0.978723 (4265 3775);
FORCEPROP 1 LAST PATH I157
J 0
(4275 3975);
DISPLAY 0.978723 (4275 3975);
PAINT WHITE (4275 3975);
DISPLAY INVISIBLE (4275 3975);
FORCEPROP 2 LAST CDS_LIB pure_quanta
J 0
(4225 3800);
DISPLAY INVISIBLE (4225 3800);
FORCEPROP 1 LAST LOCATION R274
J 0
(4270 3925);
DISPLAY 0.978723 (4270 3925);
FORCEPROP 1 LASTPIN (4225 3900) $PN 1
J 0
(4230 3862);
DISPLAY 0.787234 (4230 3862);
PAINT MONO (4230 3862);
FORCEPROP 1 LASTPIN (4225 3700) $PN 2
J 0
(4230 3710);
DISPLAY 0.787234 (4230 3710);
PAINT MONO (4230 3710);
FORCEPROP 2 LAST $SEC 1
J 0
(4275 4025);
DISPLAY 0.680851 (4275 4025);
PAINT MONO (4275 4025);
DISPLAY INVISIBLE (4275 4025);
FORCEPROP 2 LAST CDS_SEC 1
J 0
(4275 4025);
DISPLAY 1.021277 (4275 4025);
DISPLAY INVISIBLE (4275 4025);
FORCEADD OFFPAGE..1
R 2
(4475 3475);
FORCEPROP 2 LAST $XR0 29 
J 0
(4661 3475);
DISPLAY 0.638298 (4661 3475);
PAINT MONO (4661 3475);
FORCEPROP 2 LAST PATH I158
J 0
(4675 3525);
DISPLAY 0.680851 (4675 3525);
DISPLAY INVISIBLE (4675 3525);
FORCEPROP 1 LAST COMMENT_BODY TRUE
J 2
(4350 3375);
DISPLAY 0.872340 (4350 3375);
PAINT PEACH (4350 3375);
DISPLAY INVISIBLE (4350 3375);
FORCEPROP 1 LAST OFFPAGE TRUE
J 2
(4150 3350);
DISPLAY 0.872340 (4150 3350);
PAINT GREEN (4150 3350);
DISPLAY INVISIBLE (4150 3350);
FORCEPROP 2 LAST CDS_LIB standard
J 2
(4475 3475);
DISPLAY INVISIBLE (4475 3475);
FORCEADD VCCAUX15..1
(4225 4175);
FORCEPROP 3 LASTPIN (4225 4125) SIG_NAME P3V3_AUX\g
J 0
(4235 4135);
DISPLAY 0.659574 (4235 4135);
PAINT MONO (4235 4135);
DISPLAY INVISIBLE (4235 4135);
FORCEPROP 1 LAST HDL_POWER P3V3_AUX
J 1
(4225 4225);
DISPLAY 0.702128 (4225 4225);
PAINT GREEN (4225 4225);
FORCEPROP 1 LAST PATH I159
J 0
(4275 4200);
DISPLAY 0.872340 (4275 4200);
PAINT AQUA (4275 4200);
DISPLAY INVISIBLE (4275 4200);
FORCEPROP 2 LAST CDS_LIB logical_power
J 0
(4225 4175);
DISPLAY INVISIBLE (4225 4175);
FORCEADD OFFPAGE..1
R 2
(3550 4350);
FORCEPROP 2 LAST $XR1 28 
J 0
(3826 4350);
DISPLAY 0.638298 (3826 4350);
PAINT MONO (3826 4350);
FORCEPROP 2 LAST $XR0 29 
J 0
(3736 4350);
DISPLAY 0.638298 (3736 4350);
PAINT MONO (3736 4350);
FORCEPROP 2 LAST PATH I160
J 0
(3850 4400);
DISPLAY 0.680851 (3850 4400);
DISPLAY INVISIBLE (3850 4400);
FORCEPROP 1 LAST COMMENT_BODY TRUE
J 2
(3425 4250);
DISPLAY 0.872340 (3425 4250);
PAINT PEACH (3425 4250);
DISPLAY INVISIBLE (3425 4250);
FORCEPROP 1 LAST OFFPAGE TRUE
J 2
(3225 4225);
DISPLAY 0.872340 (3225 4225);
PAINT GREEN (3225 4225);
DISPLAY INVISIBLE (3225 4225);
FORCEPROP 2 LAST CDS_LIB standard
J 2
(3550 4350);
DISPLAY INVISIBLE (3550 4350);
FORCEADD Q_CAP..1
(3475 3900);
FORCEPROP 1 LAST PACK_TYPE 0402
J 0
(3525 3700);
DISPLAY 0.978723 (3525 3700);
FORCEPROP 1 LAST VALUE 0.1UF
J 0
(3525 3950);
DISPLAY 0.978723 (3525 3950);
FORCEPROP 1 LAST TOLERANCE 10%
J 0
(3525 3850);
DISPLAY 0.978723 (3525 3850);
FORCEPROP 1 LAST MATERIAL X7R
J 0
(3525 3800);
DISPLAY 0.978723 (3525 3800);
FORCEPROP 1 LAST VOLTAGE 25V
J 0
(3525 3900);
DISPLAY 0.978723 (3525 3900);
FORCEPROP 1 LAST PART_NUMBER CH4104K1B00
J 0
(3525 3750);
DISPLAY 0.978723 (3525 3750);
FORCEPROP 1 LAST PATH I161
J 0
(3525 4050);
DISPLAY 0.978723 (3525 4050);
PAINT WHITE (3525 4050);
DISPLAY INVISIBLE (3525 4050);
FORCEPROP 2 LAST CDS_LIB pure_quanta
J 0
(3475 3900);
DISPLAY INVISIBLE (3475 3900);
FORCEPROP 1 LAST LOCATION C149
J 0
(3525 4000);
DISPLAY 0.978723 (3525 4000);
FORCEPROP 1 LASTPIN (3475 4000) $PN 1
J 0
(3485 3980);
DISPLAY 0.787234 (3485 3980);
PAINT MONO (3485 3980);
FORCEPROP 1 LASTPIN (3475 3800) $PN 2
J 0
(3485 3780);
DISPLAY 0.787234 (3485 3780);
PAINT MONO (3485 3780);
FORCEPROP 2 LAST $SEC 1
J 0
(3525 4100);
DISPLAY 0.680851 (3525 4100);
PAINT MONO (3525 4100);
DISPLAY INVISIBLE (3525 4100);
FORCEPROP 2 LAST CDS_SEC 1
J 0
(3525 4100);
DISPLAY 1.021277 (3525 4100);
DISPLAY INVISIBLE (3525 4100);
FORCEADD VCCAUX15..1
R 2
(3225 4200);
FORCEPROP 3 LASTPIN (3225 4150) SIG_NAME P3V3_AUX\g
J 0
(3235 4160);
DISPLAY 0.659574 (3235 4160);
PAINT MONO (3235 4160);
DISPLAY INVISIBLE (3235 4160);
FORCEPROP 1 LAST HDL_POWER P3V3_AUX
J 1
(3225 4250);
DISPLAY 0.702128 (3225 4250);
PAINT GREEN (3225 4250);
FORCEPROP 1 LAST PATH I162
J 2
(3175 4225);
DISPLAY 0.872340 (3175 4225);
PAINT AQUA (3175 4225);
DISPLAY INVISIBLE (3175 4225);
FORCEPROP 2 LAST CDS_LIB logical_power
J 2
(3225 4200);
DISPLAY INVISIBLE (3225 4200);
FORCEADD UNIVERSAL_GND..1
R 2
(3475 3650);
FORCEPROP 3 LASTPIN (3475 3700) SIG_NAME GND\g
J 0
(3485 3710);
DISPLAY 0.659574 (3485 3710);
PAINT MONO (3485 3710);
DISPLAY INVISIBLE (3485 3710);
FORCEPROP 1 LAST HDL_POWER GND
J 1
(3450 3575);
DISPLAY 0.702128 (3450 3575);
PAINT GREEN (3450 3575);
FORCEPROP 1 LAST PATH I163
J 2
(3400 3650);
DISPLAY 0.872340 (3400 3650);
PAINT AQUA (3400 3650);
DISPLAY INVISIBLE (3400 3650);
FORCEPROP 2 LAST CDS_LIB logical_power
J 2
(3475 3650);
DISPLAY INVISIBLE (3475 3650);
FORCEADD 74HC1G126GW..1
R 2
(2850 3475);
FORCEPROP 1 LAST MATERIAL IC
J 2
(2610 3208);
DISPLAY 0.723404 (2610 3208);
PAINT GREEN (2610 3208);
FORCEPROP 2 LAST PART_TYPE SMLF
J 2
(2450 3350);
DISPLAY 1.021277 (2450 3350);
FORCEPROP 1 LAST PART_NUMBER AL1G0126007
J 2
(2610 3287);
DISPLAY 0.723404 (2610 3287);
PAINT GREEN (2610 3287);
FORCEPROP 2 LAST VALUE 74HC1G126GW
J 2
(2600 3400);
DISPLAY 1.021277 (2600 3400);
FORCEPROP 1 LAST PATH I164
J 2
(2850 3475);
DISPLAY 0.723404 (2850 3475);
PAINT GREEN (2850 3475);
DISPLAY INVISIBLE (2850 3475);
FORCEPROP 2 LAST CDS_LIB pure_quanta
J 2
(2850 3475);
DISPLAY INVISIBLE (2850 3475);
FORCEPROP 1 LAST NEEDS_NO_SIZE TRUE
J 2
(2850 3475);
DISPLAY 0.723404 (2850 3475);
PAINT GREEN (2850 3475);
DISPLAY INVISIBLE (2850 3475);
FORCEPROP 1 LAST CDS_LMAN_SYM_OUTLINE -100,100,100,-100
J 2
(2850 3475);
DISPLAY 0.468085 (2850 3475);
PAINT GREEN (2850 3475);
DISPLAY INVISIBLE (2850 3475);
FORCEPROP 2 LAST SEC_TYPE 
J 0
(2850 3525);
DISPLAY 1.021277 (2850 3525);
DISPLAY INVISIBLE (2850 3525);
FORCEPROP 1 LAST LOCATION U36
J 2
(2610 3362);
DISPLAY 0.723404 (2610 3362);
PAINT GREEN (2610 3362);
FORCEPROP 2 LASTPIN (2850 3725) $PN 1
R 1
J 0
(2840 3735);
DISPLAY 0.680851 (2840 3735);
PAINT MONO (2840 3735);
FORCEPROP 2 LASTPIN (3100 3475) $PN 2
J 0
(3110 3485);
DISPLAY 0.680851 (3110 3485);
PAINT MONO (3110 3485);
FORCEPROP 2 LASTPIN (2600 3475) $PN 4
J 2
(2590 3485);
DISPLAY 0.680851 (2590 3485);
PAINT MONO (2590 3485);
FORCEPROP 2 LASTPIN (3000 3575) $PN 5
J 0
(3010 3585);
DISPLAY 0.680851 (3010 3585);
PAINT MONO (3010 3585);
FORCEPROP 2 LASTPIN (3000 3375) $PN 3
J 0
(3010 3385);
DISPLAY 0.680851 (3010 3385);
PAINT MONO (3010 3385);
FORCEPROP 2 LAST SEC 1
J 0
(2850 3525);
DISPLAY 0.680851 (2850 3525);
PAINT MONO (2850 3525);
DISPLAY INVISIBLE (2850 3525);
FORCEADD VCCAUX15..1
(1275 4175);
FORCEPROP 3 LASTPIN (1275 4125) SIG_NAME P3V3_AUX\g
J 0
(1285 4135);
DISPLAY 0.659574 (1285 4135);
PAINT MONO (1285 4135);
DISPLAY INVISIBLE (1285 4135);
FORCEPROP 1 LAST HDL_POWER P3V3_AUX
J 1
(1275 4225);
DISPLAY 0.702128 (1275 4225);
PAINT GREEN (1275 4225);
FORCEPROP 1 LAST PATH I165
J 0
(1325 4200);
DISPLAY 0.872340 (1325 4200);
PAINT AQUA (1325 4200);
DISPLAY INVISIBLE (1325 4200);
FORCEPROP 2 LAST CDS_LIB logical_power
J 0
(1275 4175);
DISPLAY INVISIBLE (1275 4175);
FORCEADD Q_RES..2
(1275 3800);
FORCEPROP 1 LAST VALUE 100K
J 0
(1320 3875);
DISPLAY 0.978723 (1320 3875);
FORCEPROP 1 LAST PACK_TYPE 0402LF
J 0
(1315 3625);
DISPLAY 0.978723 (1315 3625);
FORCEPROP 1 LAST MATERIAL CHIP
J 0
(1315 3725);
DISPLAY 0.978723 (1315 3725);
FORCEPROP 1 LAST WATTAGE 1/16W
J 0
(1315 3775);
DISPLAY 0.978723 (1315 3775);
FORCEPROP 1 LAST TOLERANCE 1%
J 0
(1320 3825);
DISPLAY 0.978723 (1320 3825);
FORCEPROP 1 LAST PART_NUMBER CS41002FB09
J 0
(1315 3675);
DISPLAY 0.978723 (1315 3675);
FORCEPROP 1 LAST PATH I166
J 0
(1325 3975);
DISPLAY 0.978723 (1325 3975);
PAINT WHITE (1325 3975);
DISPLAY INVISIBLE (1325 3975);
FORCEPROP 2 LAST CDS_LIB pure_quanta
J 0
(1275 3800);
DISPLAY INVISIBLE (1275 3800);
FORCEPROP 1 LAST LOCATION R193
J 0
(1320 3925);
DISPLAY 0.978723 (1320 3925);
FORCEPROP 1 LASTPIN (1275 3900) $PN 1
J 0
(1280 3862);
DISPLAY 0.787234 (1280 3862);
PAINT MONO (1280 3862);
FORCEPROP 1 LASTPIN (1275 3700) $PN 2
J 0
(1280 3710);
DISPLAY 0.787234 (1280 3710);
PAINT MONO (1280 3710);
FORCEPROP 2 LAST $SEC 1
J 0
(1325 4025);
DISPLAY 0.680851 (1325 4025);
PAINT MONO (1325 4025);
DISPLAY INVISIBLE (1325 4025);
FORCEPROP 2 LAST CDS_SEC 1
J 0
(1325 4025);
DISPLAY 1.021277 (1325 4025);
DISPLAY INVISIBLE (1325 4025);
FORCEADD UNIVERSAL_GND..1
(3225 3275);
FORCEPROP 3 LASTPIN (3225 3325) SIG_NAME GND\g
J 0
(3235 3335);
DISPLAY 0.659574 (3235 3335);
PAINT MONO (3235 3335);
DISPLAY INVISIBLE (3235 3335);
FORCEPROP 1 LAST HDL_POWER GND
J 1
(3250 3200);
DISPLAY 0.702128 (3250 3200);
PAINT GREEN (3250 3200);
FORCEPROP 1 LAST PATH I167
J 0
(3300 3275);
DISPLAY 0.872340 (3300 3275);
PAINT AQUA (3300 3275);
DISPLAY INVISIBLE (3300 3275);
FORCEPROP 2 LAST CDS_LIB logical_power
J 0
(3225 3275);
DISPLAY INVISIBLE (3225 3275);
FORCEADD OFFPAGE..5
(850 3475);
FORCEPROP 2 LAST $XR0 31 
J 0
(626 3475);
DISPLAY 0.638298 (626 3475);
PAINT MONO (626 3475);
FORCEPROP 2 LAST PATH I168
J 0
(650 3525);
DISPLAY 0.680851 (650 3525);
DISPLAY INVISIBLE (650 3525);
FORCEPROP 1 LAST COMMENT_BODY TRUE
J 0
(950 3400);
DISPLAY 0.872340 (950 3400);
PAINT GREEN (950 3400);
DISPLAY INVISIBLE (950 3400);
FORCEPROP 1 LAST OFFPAGE TRUE
J 0
(1175 3350);
DISPLAY 0.872340 (1175 3350);
DISPLAY INVISIBLE (1175 3350);
FORCEPROP 2 LAST CDS_LIB standard
J 0
(850 3475);
PAINT RED (850 3475);
DISPLAY INVISIBLE (850 3475);
FORCEADD OFFPAGE..5
R 2
(4675 2275);
FORCEPROP 2 LAST $XR0 29 
J 0
(4864 2275);
DISPLAY 0.638298 (4864 2275);
PAINT MONO (4864 2275);
FORCEPROP 2 LAST PATH I169
J 0
(4875 2325);
DISPLAY 0.680851 (4875 2325);
DISPLAY INVISIBLE (4875 2325);
FORCEPROP 1 LAST COMMENT_BODY TRUE
J 2
(4575 2200);
DISPLAY 0.872340 (4575 2200);
PAINT PEACH (4575 2200);
DISPLAY INVISIBLE (4575 2200);
FORCEPROP 1 LAST OFFPAGE TRUE
J 2
(4350 2150);
DISPLAY 0.872340 (4350 2150);
PAINT GREEN (4350 2150);
DISPLAY INVISIBLE (4350 2150);
FORCEPROP 2 LAST CDS_LIB standard
J 2
(4675 2275);
PAINT MONO (4675 2275);
DISPLAY INVISIBLE (4675 2275);
FORCEADD Q_RES..2
R 2
(4100 1975);
FORCEPROP 1 LAST VALUE 100K
J 2
(4055 2050);
DISPLAY 0.978723 (4055 2050);
FORCEPROP 1 LAST PACK_TYPE 0402LF
J 2
(4060 1800);
DISPLAY 0.978723 (4060 1800);
FORCEPROP 1 LAST PART_NUMBER CS41002FB09
J 2
(4060 1850);
DISPLAY 0.978723 (4060 1850);
FORCEPROP 1 LAST MATERIAL EMPTY
J 2
(4060 1900);
DISPLAY 0.978723 (4060 1900);
FORCEPROP 1 LAST TOLERANCE 1%
J 2
(4055 2000);
DISPLAY 0.978723 (4055 2000);
FORCEPROP 1 LAST WATTAGE 1/16W
J 2
(4060 1950);
DISPLAY 0.978723 (4060 1950);
FORCEPROP 1 LAST PATH I170
J 2
(4050 2150);
DISPLAY 0.978723 (4050 2150);
PAINT WHITE (4050 2150);
DISPLAY INVISIBLE (4050 2150);
FORCEPROP 2 LAST CDS_LIB pure_quanta
J 2
(4100 1975);
DISPLAY INVISIBLE (4100 1975);
FORCEPROP 1 LAST LOCATION R219
J 2
(4055 2100);
DISPLAY 0.978723 (4055 2100);
FORCEPROP 1 LASTPIN (4100 2075) $PN 1
J 2
(4095 2037);
DISPLAY 0.787234 (4095 2037);
PAINT MONO (4095 2037);
FORCEPROP 1 LASTPIN (4100 1875) $PN 2
J 2
(4095 1885);
DISPLAY 0.787234 (4095 1885);
PAINT MONO (4095 1885);
FORCEPROP 2 LAST $SEC 1
J 0
(4050 2200);
DISPLAY 0.680851 (4050 2200);
PAINT MONO (4050 2200);
DISPLAY INVISIBLE (4050 2200);
FORCEPROP 2 LAST CDS_SEC 1
J 0
(4050 2200);
DISPLAY 1.021277 (4050 2200);
DISPLAY INVISIBLE (4050 2200);
FORCEADD UNIVERSAL_GND..1
R 2
(4100 1625);
FORCEPROP 3 LASTPIN (4100 1675) SIG_NAME GND\g
J 0
(4110 1685);
DISPLAY 0.659574 (4110 1685);
PAINT MONO (4110 1685);
DISPLAY INVISIBLE (4110 1685);
FORCEPROP 1 LAST HDL_POWER GND
J 1
(4075 1550);
DISPLAY 0.702128 (4075 1550);
PAINT GREEN (4075 1550);
FORCEPROP 1 LAST PATH I171
J 2
(4025 1625);
DISPLAY 0.872340 (4025 1625);
PAINT AQUA (4025 1625);
DISPLAY INVISIBLE (4025 1625);
FORCEPROP 2 LAST CDS_LIB logical_power
J 2
(4100 1625);
DISPLAY INVISIBLE (4100 1625);
FORCEADD Q_CAP..1
R 2
(2050 2675);
FORCEPROP 1 LAST VALUE 0.1UF
J 2
(2000 2725);
DISPLAY 0.978723 (2000 2725);
FORCEPROP 1 LAST TOLERANCE 10%
J 2
(2000 2625);
DISPLAY 0.978723 (2000 2625);
FORCEPROP 1 LAST MATERIAL X7R
J 2
(2000 2575);
DISPLAY 0.978723 (2000 2575);
FORCEPROP 1 LAST VOLTAGE 25V
J 2
(2000 2675);
DISPLAY 0.978723 (2000 2675);
FORCEPROP 1 LAST PACK_TYPE 0402
J 2
(2000 2475);
DISPLAY 0.978723 (2000 2475);
FORCEPROP 1 LAST PART_NUMBER CH4104K1B00
J 2
(2000 2525);
DISPLAY 0.978723 (2000 2525);
FORCEPROP 1 LAST PATH I172
J 2
(2000 2825);
DISPLAY 0.978723 (2000 2825);
PAINT WHITE (2000 2825);
DISPLAY INVISIBLE (2000 2825);
FORCEPROP 2 LAST CDS_LIB pure_quanta
J 2
(2050 2675);
DISPLAY INVISIBLE (2050 2675);
FORCEPROP 1 LAST LOCATION C148
J 2
(2000 2775);
DISPLAY 0.978723 (2000 2775);
FORCEPROP 1 LASTPIN (2050 2775) $PN 1
J 2
(2040 2755);
DISPLAY 0.787234 (2040 2755);
PAINT MONO (2040 2755);
FORCEPROP 1 LASTPIN (2050 2575) $PN 2
J 2
(2040 2555);
DISPLAY 0.787234 (2040 2555);
PAINT MONO (2040 2555);
FORCEPROP 2 LAST $SEC 1
J 0
(2000 2875);
DISPLAY 0.680851 (2000 2875);
PAINT MONO (2000 2875);
DISPLAY INVISIBLE (2000 2875);
FORCEPROP 2 LAST CDS_SEC 1
J 0
(2000 2875);
DISPLAY 1.021277 (2000 2875);
DISPLAY INVISIBLE (2000 2875);
FORCEADD UNIVERSAL_GND..1
(2050 2425);
FORCEPROP 3 LASTPIN (2050 2475) SIG_NAME GND\g
J 0
(2060 2485);
DISPLAY 0.659574 (2060 2485);
PAINT MONO (2060 2485);
DISPLAY INVISIBLE (2060 2485);
FORCEPROP 1 LAST HDL_POWER GND
J 1
(2075 2350);
DISPLAY 0.702128 (2075 2350);
PAINT GREEN (2075 2350);
FORCEPROP 1 LAST PATH I173
J 0
(2125 2425);
DISPLAY 0.872340 (2125 2425);
PAINT AQUA (2125 2425);
DISPLAY INVISIBLE (2125 2425);
FORCEPROP 2 LAST CDS_LIB logical_power
J 0
(2050 2425);
DISPLAY INVISIBLE (2050 2425);
FORCEADD 74HC1G126GW..1
(2625 2275);
FORCEPROP 1 LAST PART_NUMBER AL1G0126007
J 0
(2865 2087);
DISPLAY 0.723404 (2865 2087);
PAINT GREEN (2865 2087);
FORCEPROP 1 LAST MATERIAL IC
J 0
(2865 2008);
DISPLAY 0.723404 (2865 2008);
PAINT GREEN (2865 2008);
FORCEPROP 2 LAST PART_TYPE SMLF
J 0
(3025 2150);
DISPLAY 1.021277 (3025 2150);
FORCEPROP 2 LAST VALUE 74HC1G126GW
J 0
(2875 2200);
DISPLAY 1.021277 (2875 2200);
FORCEPROP 1 LAST PATH I174
J 0
(2625 2275);
DISPLAY 0.723404 (2625 2275);
PAINT GREEN (2625 2275);
DISPLAY INVISIBLE (2625 2275);
FORCEPROP 2 LAST SEC_TYPE 
J 2
(2625 2325);
DISPLAY 1.021277 (2625 2325);
DISPLAY INVISIBLE (2625 2325);
FORCEPROP 1 LAST CDS_LMAN_SYM_OUTLINE -100,100,100,-100
J 0
(2625 2275);
DISPLAY 0.468085 (2625 2275);
PAINT GREEN (2625 2275);
DISPLAY INVISIBLE (2625 2275);
FORCEPROP 1 LAST NEEDS_NO_SIZE TRUE
J 0
(2625 2275);
DISPLAY 0.723404 (2625 2275);
PAINT GREEN (2625 2275);
DISPLAY INVISIBLE (2625 2275);
FORCEPROP 2 LAST CDS_LIB pure_quanta
J 0
(2625 2275);
DISPLAY INVISIBLE (2625 2275);
FORCEPROP 1 LAST LOCATION U29
J 0
(2865 2162);
DISPLAY 0.723404 (2865 2162);
PAINT GREEN (2865 2162);
FORCEPROP 2 LASTPIN (2625 2525) $PN 1
R 1
J 0
(2667 2535);
DISPLAY 0.680851 (2667 2535);
PAINT MONO (2667 2535);
FORCEPROP 2 LASTPIN (2375 2275) $PN 2
J 2
(2365 2285);
DISPLAY 0.680851 (2365 2285);
PAINT MONO (2365 2285);
FORCEPROP 2 LASTPIN (2875 2275) $PN 4
J 0
(2885 2285);
DISPLAY 0.680851 (2885 2285);
PAINT MONO (2885 2285);
FORCEPROP 2 LASTPIN (2475 2375) $PN 5
J 2
(2465 2385);
DISPLAY 0.680851 (2465 2385);
PAINT MONO (2465 2385);
FORCEPROP 2 LASTPIN (2475 2175) $PN 3
J 2
(2465 2185);
DISPLAY 0.680851 (2465 2185);
PAINT MONO (2465 2185);
FORCEPROP 2 LAST SEC 1
J 2
(2625 2325);
DISPLAY 0.680851 (2625 2325);
PAINT MONO (2625 2325);
DISPLAY INVISIBLE (2625 2325);
FORCEADD UNIVERSAL_GND..1
R 2
(2300 1900);
FORCEPROP 3 LASTPIN (2300 1950) SIG_NAME GND\g
J 0
(2310 1960);
DISPLAY 0.659574 (2310 1960);
PAINT MONO (2310 1960);
DISPLAY INVISIBLE (2310 1960);
FORCEPROP 1 LAST HDL_POWER GND
J 1
(2275 1825);
DISPLAY 0.702128 (2275 1825);
PAINT GREEN (2275 1825);
FORCEPROP 1 LAST PATH I175
J 2
(2225 1900);
DISPLAY 0.872340 (2225 1900);
PAINT AQUA (2225 1900);
DISPLAY INVISIBLE (2225 1900);
FORCEPROP 2 LAST CDS_LIB logical_power
J 2
(2300 1900);
DISPLAY INVISIBLE (2300 1900);
FORCEADD OFFPAGE..1
(1875 3075);
FORCEPROP 2 LAST $XR1 28 
J 0
(1564 3075);
DISPLAY 0.638298 (1564 3075);
PAINT MONO (1564 3075);
FORCEPROP 2 LAST $XR0 29 
J 0
(1654 3075);
DISPLAY 0.638298 (1654 3075);
PAINT MONO (1654 3075);
FORCEPROP 2 LAST PATH I176
J 0
(1675 3125);
DISPLAY 0.680851 (1675 3125);
DISPLAY INVISIBLE (1675 3125);
FORCEPROP 1 LAST COMMENT_BODY TRUE
J 0
(2000 2975);
DISPLAY 0.872340 (2000 2975);
PAINT PEACH (2000 2975);
DISPLAY INVISIBLE (2000 2975);
FORCEPROP 1 LAST OFFPAGE TRUE
J 0
(2200 2950);
DISPLAY 0.872340 (2200 2950);
PAINT GREEN (2200 2950);
DISPLAY INVISIBLE (2200 2950);
FORCEPROP 2 LAST CDS_LIB standard
J 0
(1875 3075);
DISPLAY INVISIBLE (1875 3075);
FORCEADD VCCAUX15..1
(2300 2975);
FORCEPROP 3 LASTPIN (2300 2925) SIG_NAME P3V3_AUX\g
J 0
(2310 2935);
DISPLAY 0.659574 (2310 2935);
PAINT MONO (2310 2935);
DISPLAY INVISIBLE (2310 2935);
FORCEPROP 1 LAST HDL_POWER P3V3_AUX
J 1
(2300 3025);
DISPLAY 0.702128 (2300 3025);
PAINT GREEN (2300 3025);
FORCEPROP 1 LAST PATH I177
J 0
(2350 3000);
DISPLAY 0.872340 (2350 3000);
PAINT AQUA (2350 3000);
DISPLAY INVISIBLE (2350 3000);
FORCEPROP 2 LAST CDS_LIB logical_power
J 0
(2300 2975);
DISPLAY INVISIBLE (2300 2975);
FORCEADD OFFPAGE..1
(1000 2275);
FORCEPROP 2 LAST $XR0 31 
J 0
(779 2275);
DISPLAY 0.638298 (779 2275);
PAINT MONO (779 2275);
FORCEPROP 2 LAST PATH I178
J 0
(750 2325);
DISPLAY 0.680851 (750 2325);
DISPLAY INVISIBLE (750 2325);
FORCEPROP 1 LAST COMMENT_BODY TRUE
J 0
(1125 2175);
DISPLAY 0.872340 (1125 2175);
PAINT PEACH (1125 2175);
DISPLAY INVISIBLE (1125 2175);
FORCEPROP 1 LAST OFFPAGE TRUE
J 0
(1325 2150);
DISPLAY 0.872340 (1325 2150);
PAINT GREEN (1325 2150);
DISPLAY INVISIBLE (1325 2150);
FORCEPROP 2 LAST CDS_LIB standard
J 0
(1000 2275);
DISPLAY INVISIBLE (1000 2275);
FORCEADD UNIVERSAL_POWER..1
(3875 1150);
FORCEPROP 3 LASTPIN (3875 1100) SIG_NAME P5V_USB_REAR\g
J 0
(3885 1110);
DISPLAY 0.659574 (3885 1110);
PAINT MONO (3885 1110);
DISPLAY INVISIBLE (3885 1110);
FORCEPROP 1 LAST HDL_POWER P5V_USB_REAR
J 1
(3875 1200);
DISPLAY 0.702128 (3875 1200);
PAINT GREEN (3875 1200);
FORCEPROP 1 LAST PATH I179
J 0
(3925 1175);
DISPLAY 0.872340 (3925 1175);
PAINT AQUA (3925 1175);
DISPLAY INVISIBLE (3925 1175);
FORCEPROP 2 LAST CDS_LIB logical_power
J 0
(3875 1150);
DISPLAY INVISIBLE (3875 1150);
FORCEADD OFFPAGE..1
(2425 725);
FORCEPROP 2 LAST $XR0 29 
J 0
(2204 725);
DISPLAY 0.638298 (2204 725);
PAINT MONO (2204 725);
FORCEPROP 2 LAST PATH I181
J 0
(2225 775);
DISPLAY 0.680851 (2225 775);
DISPLAY INVISIBLE (2225 775);
FORCEPROP 1 LAST COMMENT_BODY TRUE
J 0
(2550 625);
DISPLAY 0.872340 (2550 625);
PAINT GREEN (2550 625);
DISPLAY INVISIBLE (2550 625);
FORCEPROP 1 LAST OFFPAGE TRUE
J 0
(2750 600);
DISPLAY 0.872340 (2750 600);
DISPLAY INVISIBLE (2750 600);
FORCEPROP 2 LAST CDS_LIB standard
J 0
(2425 725);
PAINT RED (2425 725);
DISPLAY INVISIBLE (2425 725);
FORCEADD UNIVERSAL_GND..1
(4875 150);
FORCEPROP 3 LASTPIN (4875 200) SIG_NAME GND\g
J 0
(4885 210);
DISPLAY 0.659574 (4885 210);
PAINT MONO (4885 210);
DISPLAY INVISIBLE (4885 210);
FORCEPROP 1 LAST HDL_POWER GND
J 1
(4900 75);
DISPLAY 0.702128 (4900 75);
PAINT GREEN (4900 75);
FORCEPROP 1 LAST PATH I182
J 0
(4950 150);
DISPLAY 0.872340 (4950 150);
PAINT AQUA (4950 150);
DISPLAY INVISIBLE (4950 150);
FORCEPROP 2 LAST CDS_LIB logical_power
J 0
(4875 150);
DISPLAY INVISIBLE (4875 150);
FORCEADD UNIVERSAL_GND..1
(3875 75);
FORCEPROP 3 LASTPIN (3875 125) SIG_NAME GND\g
J 0
(3885 135);
DISPLAY 0.659574 (3885 135);
PAINT MONO (3885 135);
DISPLAY INVISIBLE (3885 135);
FORCEPROP 1 LAST HDL_POWER GND
J 1
(3900 0);
DISPLAY 0.702128 (3900 0);
PAINT GREEN (3900 0);
FORCEPROP 1 LAST PATH I183
J 0
(3950 75);
DISPLAY 0.872340 (3950 75);
PAINT AQUA (3950 75);
DISPLAY INVISIBLE (3950 75);
FORCEPROP 2 LAST CDS_LIB logical_power
J 0
(3875 75);
DISPLAY INVISIBLE (3875 75);
FORCEADD Q_RES..2
R 2
(3775 125);
FORCEPROP 1 LAST TOLERANCE 1%
J 2
(3730 150);
DISPLAY 0.978723 (3730 150);
FORCEPROP 1 LAST VALUE 20K
J 2
(3730 200);
DISPLAY 0.978723 (3730 200);
FORCEPROP 1 LAST PACK_TYPE 0402LF
J 2
(3735 -50);
DISPLAY 0.978723 (3735 -50);
FORCEPROP 1 LAST MATERIAL CHIP
J 2
(3735 50);
DISPLAY 0.978723 (3735 50);
FORCEPROP 1 LAST WATTAGE 1/16W
J 2
(3735 100);
DISPLAY 0.978723 (3735 100);
FORCEPROP 1 LAST PART_NUMBER CS32002FB06
J 2
(3735 0);
DISPLAY 0.978723 (3735 0);
FORCEPROP 1 LAST PATH I184
J 2
(3725 300);
DISPLAY 0.978723 (3725 300);
PAINT WHITE (3725 300);
DISPLAY INVISIBLE (3725 300);
FORCEPROP 2 LAST SEC_TYPE 0402LF
J 0
(3725 350);
DISPLAY 1.021277 (3725 350);
DISPLAY INVISIBLE (3725 350);
FORCEPROP 2 LAST CDS_LIB pure_quanta
J 2
(3775 125);
DISPLAY INVISIBLE (3775 125);
FORCEPROP 1 LAST LOCATION R205
J 2
(3730 250);
DISPLAY 0.978723 (3730 250);
FORCEPROP 1 LASTPIN (3775 225) $PN 1
J 2
(3770 187);
DISPLAY 0.787234 (3770 187);
PAINT MONO (3770 187);
FORCEPROP 1 LASTPIN (3775 25) $PN 2
J 2
(3770 35);
DISPLAY 0.787234 (3770 35);
PAINT MONO (3770 35);
FORCEPROP 2 LAST SEC 1
J 0
(3725 350);
DISPLAY 0.680851 (3725 350);
PAINT MONO (3725 350);
DISPLAY INVISIBLE (3725 350);
FORCEADD UNIVERSAL_GND..1
R 2
(3775 -200);
FORCEPROP 3 LASTPIN (3775 -150) SIG_NAME GND\g
J 0
(3785 -140);
DISPLAY 0.659574 (3785 -140);
PAINT MONO (3785 -140);
DISPLAY INVISIBLE (3785 -140);
FORCEPROP 1 LAST HDL_POWER GND
J 1
(3750 -275);
DISPLAY 0.702128 (3750 -275);
PAINT GREEN (3750 -275);
FORCEPROP 1 LAST PATH I185
J 2
(3700 -200);
DISPLAY 0.872340 (3700 -200);
PAINT AQUA (3700 -200);
DISPLAY INVISIBLE (3700 -200);
FORCEPROP 2 LAST CDS_LIB logical_power
J 2
(3775 -200);
DISPLAY INVISIBLE (3775 -200);
FORCEADD OFFPAGE..5
(2425 425);
FORCEPROP 2 LAST $XR0 29 
J 0
(2171 425);
DISPLAY 0.638298 (2171 425);
PAINT MONO (2171 425);
FORCEPROP 2 LAST PATH I186
J 0
(2175 475);
DISPLAY 0.680851 (2175 475);
DISPLAY INVISIBLE (2175 475);
FORCEPROP 1 LAST COMMENT_BODY TRUE
J 0
(2525 350);
DISPLAY 0.872340 (2525 350);
PAINT GREEN (2525 350);
DISPLAY INVISIBLE (2525 350);
FORCEPROP 1 LAST OFFPAGE TRUE
J 0
(2750 300);
DISPLAY 0.872340 (2750 300);
DISPLAY INVISIBLE (2750 300);
FORCEPROP 2 LAST CDS_LIB standard
J 0
(2425 425);
PAINT RED (2425 425);
DISPLAY INVISIBLE (2425 425);
FORCEADD OFFPAGE..5
(2425 325);
FORCEPROP 2 LAST $XR0 29 
J 0
(2201 325);
DISPLAY 0.638298 (2201 325);
PAINT MONO (2201 325);
FORCEPROP 2 LAST PATH I187
J 0
(2175 375);
DISPLAY 0.680851 (2175 375);
DISPLAY INVISIBLE (2175 375);
FORCEPROP 1 LAST COMMENT_BODY TRUE
J 0
(2525 250);
DISPLAY 0.872340 (2525 250);
PAINT PEACH (2525 250);
DISPLAY INVISIBLE (2525 250);
FORCEPROP 1 LAST OFFPAGE TRUE
J 0
(2750 200);
DISPLAY 0.872340 (2750 200);
PAINT GREEN (2750 200);
DISPLAY INVISIBLE (2750 200);
FORCEPROP 2 LAST CDS_LIB standard
J 0
(2425 325);
PAINT RED (2425 325);
DISPLAY INVISIBLE (2425 325);
FORCEADD OFFPAGE..1
(2425 625);
FORCEPROP 2 LAST $XR0 29 
J 0
(2204 625);
DISPLAY 0.638298 (2204 625);
PAINT MONO (2204 625);
FORCEPROP 2 LAST PATH I188
J 0
(2225 675);
DISPLAY 0.680851 (2225 675);
DISPLAY INVISIBLE (2225 675);
FORCEPROP 1 LAST COMMENT_BODY TRUE
J 0
(2550 525);
DISPLAY 0.872340 (2550 525);
PAINT PEACH (2550 525);
DISPLAY INVISIBLE (2550 525);
FORCEPROP 1 LAST OFFPAGE TRUE
J 0
(2750 500);
DISPLAY 0.872340 (2750 500);
PAINT GREEN (2750 500);
DISPLAY INVISIBLE (2750 500);
FORCEPROP 2 LAST CDS_LIB standard
J 0
(2425 625);
PAINT RED (2425 625);
DISPLAY INVISIBLE (2425 625);
FORCEADD OFFPAGE..6
(2425 575);
FORCEPROP 2 LAST $XR0 29 
J 0
(2176 575);
DISPLAY 0.638298 (2176 575);
PAINT MONO (2176 575);
FORCEPROP 2 LAST PATH I189
J 0
(2200 625);
DISPLAY 0.680851 (2200 625);
DISPLAY INVISIBLE (2200 625);
FORCEPROP 1 LAST COMMENT_BODY TRUE
J 0
(2525 500);
DISPLAY 0.872340 (2525 500);
PAINT PEACH (2525 500);
DISPLAY INVISIBLE (2525 500);
FORCEPROP 1 LAST OFFPAGE TRUE
J 0
(2750 450);
DISPLAY 0.872340 (2750 450);
PAINT GREEN (2750 450);
DISPLAY INVISIBLE (2750 450);
FORCEPROP 2 LAST CDS_LIB standard
J 0
(2425 575);
PAINT RED (2425 575);
DISPLAY INVISIBLE (2425 575);
FORCEADD OFFPAGE..6
(2425 475);
FORCEPROP 2 LAST $XR0 29 
J 0
(2176 475);
DISPLAY 0.638298 (2176 475);
PAINT MONO (2176 475);
FORCEPROP 2 LAST PATH I190
J 0
(2200 525);
DISPLAY 0.680851 (2200 525);
DISPLAY INVISIBLE (2200 525);
FORCEPROP 1 LAST COMMENT_BODY TRUE
J 0
(2525 400);
DISPLAY 0.872340 (2525 400);
PAINT PEACH (2525 400);
DISPLAY INVISIBLE (2525 400);
FORCEPROP 1 LAST OFFPAGE TRUE
J 0
(2750 350);
DISPLAY 0.872340 (2750 350);
PAINT GREEN (2750 350);
DISPLAY INVISIBLE (2750 350);
FORCEPROP 2 LAST CDS_LIB standard
J 0
(2425 475);
PAINT RED (2425 475);
DISPLAY INVISIBLE (2425 475);
FORCEADD OFFPAGE..5
(1125 375);
FORCEPROP 2 LAST $XR0 28 
J 0
(871 375);
DISPLAY 0.638298 (871 375);
PAINT MONO (871 375);
FORCEPROP 2 LAST $XR1 29 
J 0
(781 375);
DISPLAY 0.638298 (781 375);
PAINT MONO (781 375);
FORCEPROP 2 LAST CDS_LIB standard
J 0
(1125 375);
PAINT RED (1125 375);
DISPLAY INVISIBLE (1125 375);
FORCEPROP 2 LAST PATH I192
J 0
(875 425);
DISPLAY 0.680851 (875 425);
DISPLAY INVISIBLE (875 425);
FORCEPROP 1 LAST COMMENT_BODY TRUE
J 0
(1225 300);
DISPLAY 0.872340 (1225 300);
PAINT GREEN (1225 300);
DISPLAY INVISIBLE (1225 300);
FORCEPROP 1 LAST OFFPAGE TRUE
J 0
(1450 250);
DISPLAY 0.872340 (1450 250);
DISPLAY INVISIBLE (1450 250);
FORCEADD Q_CAP..1
(1750 1450);
FORCEPROP 1 LAST TOLERANCE 10%
J 0
(1800 1400);
DISPLAY 0.510638 (1800 1400);
PAINT SKYBLUE (1800 1400);
FORCEPROP 1 LAST MATERIAL X7R
J 0
(1800 1350);
DISPLAY 0.510638 (1800 1350);
PAINT SKYBLUE (1800 1350);
FORCEPROP 1 LAST VALUE 470PF
J 0
(1800 1500);
DISPLAY 0.510638 (1800 1500);
PAINT SKYBLUE (1800 1500);
FORCEPROP 1 LAST VOLTAGE 50V
J 0
(1800 1450);
DISPLAY 0.510638 (1800 1450);
PAINT SKYBLUE (1800 1450);
FORCEPROP 1 LAST PACK_TYPE 0402
J 0
(1800 1300);
DISPLAY 0.510638 (1800 1300);
PAINT SKYBLUE (1800 1300);
FORCEPROP 1 LAST PATH I193
J 0
(1800 1600);
DISPLAY 0.978723 (1800 1600);
PAINT WHITE (1800 1600);
DISPLAY INVISIBLE (1800 1600);
FORCEPROP 1 LAST PART_NUMBER TMP_QCH14706KB18
J 0
(1800 1300);
DISPLAY 0.510638 (1800 1300);
PAINT WHITE (1800 1300);
DISPLAY INVISIBLE (1800 1300);
FORCEPROP 2 LAST CDS_LIB pure_quanta
J 0
(1750 1450);
PAINT RED (1750 1450);
DISPLAY INVISIBLE (1750 1450);
FORCEPROP 1 LAST LOCATION C179
J 0
(1800 1550);
DISPLAY 0.702128 (1800 1550);
PAINT YELLOW (1800 1550);
FORCEPROP 1 LASTPIN (1750 1550) $PN 1
J 0
(1760 1530);
DISPLAY 0.808511 (1760 1530);
PAINT WHITE (1760 1530);
FORCEPROP 1 LASTPIN (1750 1350) $PN 2
J 0
(1760 1330);
DISPLAY 0.808511 (1760 1330);
PAINT WHITE (1760 1330);
FORCEPROP 2 LAST $SEC 1
J 0
(1800 1650);
DISPLAY 0.680851 (1800 1650);
PAINT MONO (1800 1650);
DISPLAY INVISIBLE (1800 1650);
FORCEPROP 2 LAST CDS_SEC 1
J 0
(1800 1650);
DISPLAY 1.021277 (1800 1650);
DISPLAY INVISIBLE (1800 1650);
FORCEADD Q_CAP..1
(1400 1450);
FORCEPROP 1 LAST PACK_TYPE 0402
J 0
(1450 1300);
DISPLAY 0.510638 (1450 1300);
PAINT SKYBLUE (1450 1300);
FORCEPROP 1 LAST MATERIAL X7R
J 0
(1450 1350);
DISPLAY 0.510638 (1450 1350);
PAINT SKYBLUE (1450 1350);
FORCEPROP 1 LAST VALUE 470PF
J 0
(1450 1500);
DISPLAY 0.510638 (1450 1500);
PAINT SKYBLUE (1450 1500);
FORCEPROP 1 LAST TOLERANCE 10%
J 0
(1450 1400);
DISPLAY 0.510638 (1450 1400);
PAINT SKYBLUE (1450 1400);
FORCEPROP 1 LAST VOLTAGE 50V
J 0
(1450 1450);
DISPLAY 0.510638 (1450 1450);
PAINT SKYBLUE (1450 1450);
FORCEPROP 1 LAST PATH I194
J 0
(1450 1600);
DISPLAY 0.978723 (1450 1600);
PAINT WHITE (1450 1600);
DISPLAY INVISIBLE (1450 1600);
FORCEPROP 1 LAST PART_NUMBER TMP_QCH14706KB18
J 0
(1450 1300);
DISPLAY 0.510638 (1450 1300);
PAINT WHITE (1450 1300);
DISPLAY INVISIBLE (1450 1300);
FORCEPROP 2 LAST CDS_LIB pure_quanta
J 0
(1400 1450);
PAINT RED (1400 1450);
DISPLAY INVISIBLE (1400 1450);
FORCEPROP 1 LAST LOCATION C178
J 0
(1450 1550);
DISPLAY 0.702128 (1450 1550);
PAINT YELLOW (1450 1550);
FORCEPROP 1 LASTPIN (1400 1550) $PN 1
J 0
(1410 1530);
DISPLAY 0.808511 (1410 1530);
PAINT WHITE (1410 1530);
FORCEPROP 1 LASTPIN (1400 1350) $PN 2
J 0
(1410 1330);
DISPLAY 0.808511 (1410 1330);
PAINT WHITE (1410 1330);
FORCEPROP 2 LAST $SEC 1
J 0
(1450 1650);
DISPLAY 0.680851 (1450 1650);
PAINT MONO (1450 1650);
DISPLAY INVISIBLE (1450 1650);
FORCEPROP 2 LAST CDS_SEC 1
J 0
(1450 1650);
DISPLAY 1.021277 (1450 1650);
DISPLAY INVISIBLE (1450 1650);
FORCEADD UNIVERSAL_GND..1
(1750 1075);
FORCEPROP 3 LASTPIN (1750 1125) SIG_NAME GND\g
J 0
(1760 1135);
DISPLAY 0.659574 (1760 1135);
PAINT MONO (1760 1135);
DISPLAY INVISIBLE (1760 1135);
FORCEPROP 1 LAST HDL_POWER GND
J 1
(1775 1000);
DISPLAY 0.702128 (1775 1000);
PAINT GREEN (1775 1000);
FORCEPROP 1 LAST PATH I195
J 0
(1825 1075);
DISPLAY 0.872340 (1825 1075);
PAINT AQUA (1825 1075);
DISPLAY INVISIBLE (1825 1075);
FORCEPROP 2 LAST CDS_LIB logical_power
J 0
(1750 1075);
DISPLAY INVISIBLE (1750 1075);
FORCEADD UNIVERSAL_POWER..1
(825 1725);
FORCEPROP 3 LASTPIN (825 1675) SIG_NAME P5V_USB_REAR\g
J 0
(835 1685);
DISPLAY 0.659574 (835 1685);
PAINT MONO (835 1685);
DISPLAY INVISIBLE (835 1685);
FORCEPROP 1 LAST HDL_POWER P5V_USB_REAR
J 1
(1000 1775);
DISPLAY 0.702128 (1000 1775);
PAINT GREEN (1000 1775);
FORCEPROP 1 LAST PATH I197
J 0
(875 1750);
DISPLAY 0.872340 (875 1750);
PAINT AQUA (875 1750);
DISPLAY INVISIBLE (875 1750);
FORCEPROP 2 LAST CDS_LIB logical_power
J 0
(825 1725);
PAINT RED (825 1725);
DISPLAY INVISIBLE (825 1725);
FORCEADD OFFPAGE..5
(2425 -450);
FORCEPROP 2 LAST $XR1 36 
J 0
(2111 -450);
DISPLAY 0.638298 (2111 -450);
PAINT MONO (2111 -450);
FORCEPROP 2 LAST $XR0 13 
J 0
(2201 -450);
DISPLAY 0.638298 (2201 -450);
PAINT MONO (2201 -450);
FORCEPROP 2 LAST PATH I199
J 2
(2050 -400);
DISPLAY 0.680851 (2050 -400);
DISPLAY INVISIBLE (2050 -400);
FORCEPROP 1 LAST COMMENT_BODY TRUE
J 0
(2525 -525);
DISPLAY 0.872340 (2525 -525);
PAINT PEACH (2525 -525);
DISPLAY INVISIBLE (2525 -525);
FORCEPROP 1 LAST OFFPAGE TRUE
J 0
(2750 -575);
DISPLAY 0.872340 (2750 -575);
PAINT GREEN (2750 -575);
DISPLAY INVISIBLE (2750 -575);
FORCEPROP 2 LAST CDS_LIB standard
J 0
(2425 -450);
PAINT MONO (2425 -450);
DISPLAY INVISIBLE (2425 -450);
FORCEADD UNIVERSAL_GND..1
(2475 -1850);
FORCEPROP 3 LASTPIN (2475 -1800) SIG_NAME GND\g
J 0
(2485 -1790);
DISPLAY 0.659574 (2485 -1790);
PAINT MONO (2485 -1790);
DISPLAY INVISIBLE (2485 -1790);
FORCEPROP 1 LAST HDL_POWER GND
J 1
(2500 -1925);
DISPLAY 0.702128 (2500 -1925);
PAINT GREEN (2500 -1925);
FORCEPROP 1 LAST PATH I200
J 0
(2550 -1850);
DISPLAY 0.872340 (2550 -1850);
PAINT AQUA (2550 -1850);
DISPLAY INVISIBLE (2550 -1850);
FORCEPROP 2 LAST CDS_LIB logical_power
J 0
(2475 -1850);
DISPLAY INVISIBLE (2475 -1850);
FORCEADD Q_RES..1
R 2
(3575 -450);
FORCEPROP 1 LAST TOLERANCE 5%
J 2
(3575 -500);
DISPLAY 0.510638 (3575 -500);
PAINT SKYBLUE (3575 -500);
FORCEPROP 1 LAST WATTAGE 1/16W
J 0
(3600 -550);
DISPLAY 0.510638 (3600 -550);
PAINT SKYBLUE (3600 -550);
FORCEPROP 1 LAST PACK_TYPE 0402LF
J 2
(3450 -550);
DISPLAY 0.510638 (3450 -550);
PAINT SKYBLUE (3450 -550);
FORCEPROP 1 LAST PART_NUMBER CS00002JB13
J 2
(3900 -500);
DISPLAY 0.510638 (3900 -500);
PAINT WHITE (3900 -500);
FORCEPROP 1 LAST MATERIAL CHIP
J 2
(3575 -550);
DISPLAY 0.510638 (3575 -550);
PAINT SKYBLUE (3575 -550);
FORCEPROP 1 LAST VALUE 0
J 0
(3600 -500);
DISPLAY 0.510638 (3600 -500);
PAINT SKYBLUE (3600 -500);
FORCEPROP 2 LAST CDS_LIB pure_quanta
J 2
(3575 -450);
DISPLAY INVISIBLE (3575 -450);
FORCEPROP 1 LAST PATH I201
J 2
(3625 -300);
DISPLAY 0.978723 (3625 -300);
PAINT WHITE (3625 -300);
DISPLAY INVISIBLE (3625 -300);
FORCEPROP 1 LAST LOCATION R707
J 2
(3525 -425);
DISPLAY 0.702128 (3525 -425);
PAINT YELLOW (3525 -425);
FORCEPROP 0 LAST $SEC 1
J 2
(3525 -375);
DISPLAY 0.680851 (3525 -375);
PAINT MONO (3525 -375);
DISPLAY INVISIBLE (3525 -375);
FORCEPROP 0 LAST CDS_SEC 1
J 2
(3525 -375);
DISPLAY 1.021277 (3525 -375);
DISPLAY INVISIBLE (3525 -375);
FORCEPROP 1 LASTPIN (3675 -450) $PN 1
J 2
(3663 -438);
DISPLAY 0.808511 (3663 -438);
PAINT WHITE (3663 -438);
DISPLAY INVISIBLE (3663 -438);
FORCEPROP 1 LASTPIN (3475 -450) $PN 2
J 2
(3513 -438);
DISPLAY 0.808511 (3513 -438);
PAINT WHITE (3513 -438);
DISPLAY INVISIBLE (3513 -438);
FORCEADD 2N7002A7..1
R 2
(3150 -1525);
FORCEPROP 1 LAST MATERIAL IC
J 2
(3447 -1195);
DISPLAY 0.723404 (3447 -1195);
PAINT GREEN (3447 -1195);
FORCEPROP 1 LAST PART_NUMBER BAM70020068
J 2
(3447 -1140);
DISPLAY 0.723404 (3447 -1140);
PAINT GREEN (3447 -1140);
FORCEPROP 2 LAST VALUE 2N7002A-7
J 2
(3425 -1050);
DISPLAY 0.680851 (3425 -1050);
FORCEPROP 2 LAST PART_TYPE SMLF
J 2
(3425 -1000);
DISPLAY 0.680851 (3425 -1000);
FORCEPROP 1 LAST PATH I202
J 2
(3150 -1525);
DISPLAY 0.723404 (3150 -1525);
PAINT GREEN (3150 -1525);
DISPLAY INVISIBLE (3150 -1525);
FORCEPROP 1 LAST NEEDS_NO_SIZE TRUE
J 2
(3150 -1525);
DISPLAY 0.723404 (3150 -1525);
PAINT GREEN (3150 -1525);
DISPLAY INVISIBLE (3150 -1525);
FORCEPROP 1 LAST CDS_LMAN_SYM_OUTLINE -300,325,300,-325
J 2
(3150 -1525);
DISPLAY 0.468085 (3150 -1525);
PAINT GREEN (3150 -1525);
DISPLAY INVISIBLE (3150 -1525);
FORCEPROP 2 LAST CDS_LIB pure_quanta
J 2
(3150 -1525);
DISPLAY INVISIBLE (3150 -1525);
FORCEPROP 1 LAST LOCATION Q6
J 2
(3447 -1090);
DISPLAY 0.723404 (3447 -1090);
PAINT GREEN (3447 -1090);
FORCEPROP 0 LASTPIN (3600 -1250) $PN D
J 0
(3610 -1240);
DISPLAY 0.680851 (3610 -1240);
PAINT MONO (3610 -1240);
FORCEPROP 0 LASTPIN (3600 -1500) $PN G
J 0
(3610 -1490);
DISPLAY 0.680851 (3610 -1490);
PAINT MONO (3610 -1490);
FORCEPROP 0 LASTPIN (2700 -1750) $PN S
J 2
(2690 -1740);
DISPLAY 0.680851 (2690 -1740);
PAINT MONO (2690 -1740);
FORCEPROP 0 LAST $SEC 1
J 2
(3425 -950);
DISPLAY 0.680851 (3425 -950);
PAINT MONO (3425 -950);
DISPLAY INVISIBLE (3425 -950);
FORCEPROP 0 LAST CDS_SEC 1
J 2
(3425 -950);
DISPLAY 0.680851 (3425 -950);
DISPLAY INVISIBLE (3425 -950);
FORCEADD VCCAUX15..1
R 2
(4650 50);
FORCEPROP 3 LASTPIN (4650 0) SIG_NAME P3V3_AUX\g
J 0
(4660 10);
DISPLAY 0.659574 (4660 10);
PAINT MONO (4660 10);
DISPLAY INVISIBLE (4660 10);
FORCEPROP 1 LAST HDL_POWER P3V3_AUX
J 1
(4650 100);
DISPLAY 0.702128 (4650 100);
PAINT GREEN (4650 100);
FORCEPROP 2 LAST CDS_LIB logical_power
J 2
(4650 50);
DISPLAY INVISIBLE (4650 50);
FORCEPROP 1 LAST PATH I203
J 2
(4600 75);
DISPLAY 0.872340 (4600 75);
PAINT AQUA (4600 75);
DISPLAY INVISIBLE (4600 75);
FORCEADD Q_RES..2
R 2
(4650 -175);
FORCEPROP 1 LAST MATERIAL CHIP
J 2
(4610 -250);
DISPLAY 0.978723 (4610 -250);
FORCEPROP 1 LAST WATTAGE 1/16W
J 2
(4610 -200);
DISPLAY 0.978723 (4610 -200);
FORCEPROP 1 LAST TOLERANCE 1%
J 2
(4605 -150);
DISPLAY 0.978723 (4605 -150);
FORCEPROP 1 LAST VALUE 4.7K
J 2
(4605 -100);
DISPLAY 0.978723 (4605 -100);
FORCEPROP 1 LAST PART_NUMBER CS24702FB06
J 2
(4610 -300);
DISPLAY 0.978723 (4610 -300);
FORCEPROP 1 LAST PACK_TYPE 0402LF
J 2
(4610 -350);
DISPLAY 0.978723 (4610 -350);
FORCEPROP 2 LAST CDS_LIB pure_quanta
J 2
(4650 -175);
DISPLAY INVISIBLE (4650 -175);
FORCEPROP 1 LAST PATH I204
J 2
(4600 0);
DISPLAY 0.978723 (4600 0);
PAINT WHITE (4600 0);
DISPLAY INVISIBLE (4600 0);
FORCEPROP 1 LAST LOCATION R730
J 2
(4605 -50);
DISPLAY 0.978723 (4605 -50);
FORCEPROP 1 LASTPIN (4650 -75) $PN 1
J 2
(4645 -113);
DISPLAY 0.787234 (4645 -113);
PAINT MONO (4645 -113);
FORCEPROP 1 LASTPIN (4650 -275) $PN 2
J 2
(4645 -265);
DISPLAY 0.787234 (4645 -265);
PAINT MONO (4645 -265);
FORCEPROP 0 LAST $SEC 1
J 2
(4600 0);
DISPLAY 0.680851 (4600 0);
PAINT MONO (4600 0);
DISPLAY INVISIBLE (4600 0);
FORCEPROP 0 LAST CDS_SEC 1
J 2
(4600 0);
DISPLAY 0.680851 (4600 0);
DISPLAY INVISIBLE (4600 0);
FORCEADD OFFPAGE..1
R 2
(4425 -1500);
FORCEPROP 2 LAST $XR1 28 
J 0
(4701 -1500);
DISPLAY 0.638298 (4701 -1500);
PAINT MONO (4701 -1500);
FORCEPROP 2 LAST $XR0 29 
J 0
(4611 -1500);
DISPLAY 0.638298 (4611 -1500);
PAINT MONO (4611 -1500);
FORCEPROP 2 LAST PATH I205
J 2
(4675 -1450);
DISPLAY 0.680851 (4675 -1450);
DISPLAY INVISIBLE (4675 -1450);
FORCEPROP 1 LAST COMMENT_BODY TRUE
J 2
(4300 -1600);
DISPLAY 0.872340 (4300 -1600);
PAINT PEACH (4300 -1600);
DISPLAY INVISIBLE (4300 -1600);
FORCEPROP 1 LAST OFFPAGE TRUE
J 2
(4100 -1625);
DISPLAY 0.872340 (4100 -1625);
PAINT GREEN (4100 -1625);
DISPLAY INVISIBLE (4100 -1625);
FORCEPROP 2 LAST CDS_LIB standard
J 2
(4425 -1500);
DISPLAY INVISIBLE (4425 -1500);
FORCEADD PI3PCIE3212ZBEX..1
(-1675 -825);
FORCEPROP 1 LAST MATERIAL IC
J 0
(-1903 -320);
DISPLAY 0.723404 (-1903 -320);
PAINT GREEN (-1903 -320);
FORCEPROP 1 LAST PART_NUMBER AL003212003
J 0
(-1903 -231);
DISPLAY 0.723404 (-1903 -231);
PAINT GREEN (-1903 -231);
FORCEPROP 2 LAST PART_TYPE SMLF
J 0
(-1900 -50);
DISPLAY 0.680851 (-1900 -50);
FORCEPROP 2 LAST VALUE PI3PCIE3212ZBEX
J 0
(-1900 -100);
DISPLAY 0.680851 (-1900 -100);
FORCEPROP 1 LAST CDS_LMAN_SYM_OUTLINE -225,500,225,-500
J 0
(-1675 -825);
DISPLAY 0.468085 (-1675 -825);
PAINT GREEN (-1675 -825);
DISPLAY INVISIBLE (-1675 -825);
FORCEPROP 1 LAST PIN_NAMES_ROTATE True
J 0
(-1675 -825);
DISPLAY 0.489362 (-1675 -825);
PAINT GREEN (-1675 -825);
DISPLAY INVISIBLE (-1675 -825);
FORCEPROP 1 LAST PATH I206
J 0
(-1450 -1325);
DISPLAY 0.723404 (-1450 -1325);
PAINT GREEN (-1450 -1325);
DISPLAY INVISIBLE (-1450 -1325);
FORCEPROP 2 LAST CDS_LIB pure_quanta
J 0
(-1675 -825);
DISPLAY INVISIBLE (-1675 -825);
FORCEPROP 1 LAST $LOCATION U22
J 0
(-1903 -147);
DISPLAY 0.723404 (-1903 -147);
PAINT GREEN (-1903 -147);
FORCEPROP 0 LASTPIN (-2050 -725) $PN 4
J 2
(-2060 -715);
DISPLAY 0.680851 (-2060 -715);
PAINT MONO (-2060 -715);
FORCEPROP 0 LASTPIN (-2050 -675) $PN 3
J 2
(-2060 -665);
DISPLAY 0.680851 (-2060 -665);
PAINT MONO (-2060 -665);
FORCEPROP 0 LASTPIN (-2050 -825) $PN 8
J 2
(-2060 -815);
DISPLAY 0.680851 (-2060 -815);
PAINT MONO (-2060 -815);
FORCEPROP 0 LASTPIN (-2050 -775) $PN 7
J 2
(-2060 -765);
DISPLAY 0.680851 (-2060 -765);
PAINT MONO (-2060 -765);
FORCEPROP 0 LASTPIN (-1300 -475) $PN 18
J 0
(-1290 -465);
DISPLAY 0.680851 (-1290 -465);
PAINT MONO (-1290 -465);
FORCEPROP 0 LASTPIN (-1300 -425) $PN 19
J 0
(-1290 -415);
DISPLAY 0.680851 (-1290 -415);
PAINT MONO (-1290 -415);
FORCEPROP 0 LASTPIN (-1300 -575) $PN 16
J 0
(-1290 -565);
DISPLAY 0.680851 (-1290 -565);
PAINT MONO (-1290 -565);
FORCEPROP 0 LASTPIN (-1300 -525) $PN 17
J 0
(-1290 -515);
DISPLAY 0.680851 (-1290 -515);
PAINT MONO (-1290 -515);
FORCEPROP 0 LASTPIN (-1300 -725) $PN 14
J 0
(-1290 -715);
DISPLAY 0.680851 (-1290 -715);
PAINT MONO (-1290 -715);
FORCEPROP 0 LASTPIN (-1300 -675) $PN 15
J 0
(-1290 -665);
DISPLAY 0.680851 (-1290 -665);
PAINT MONO (-1290 -665);
FORCEPROP 0 LASTPIN (-1300 -825) $PN 12
J 0
(-1290 -815);
DISPLAY 0.680851 (-1290 -815);
PAINT MONO (-1290 -815);
FORCEPROP 0 LASTPIN (-1300 -775) $PN 13
J 0
(-1290 -765);
DISPLAY 0.680851 (-1290 -765);
PAINT MONO (-1290 -765);
FORCEPROP 0 LASTPIN (-1300 -1125) $PN 20
J 0
(-1290 -1115);
DISPLAY 0.680851 (-1290 -1115);
PAINT MONO (-1290 -1115);
FORCEPROP 0 LASTPIN (-1300 -1175) $PN 5
J 0
(-1290 -1165);
DISPLAY 0.680851 (-1290 -1165);
PAINT MONO (-1290 -1165);
FORCEPROP 0 LASTPIN (-1300 -1225) $PN 11
J 0
(-1290 -1215);
DISPLAY 0.680851 (-1290 -1215);
PAINT MONO (-1290 -1215);
FORCEPROP 0 LASTPIN (-2050 -1075) $PN 2
J 2
(-2060 -1065);
DISPLAY 0.680851 (-2060 -1065);
PAINT MONO (-2060 -1065);
FORCEPROP 0 LASTPIN (-2050 -925) $PN 9
J 2
(-2060 -915);
DISPLAY 0.680851 (-2060 -915);
PAINT MONO (-2060 -915);
FORCEPROP 0 LASTPIN (-2050 -1225) $PN TH
J 2
(-2060 -1215);
DISPLAY 0.680851 (-2060 -1215);
PAINT MONO (-2060 -1215);
FORCEPROP 0 LASTPIN (-2050 -425) $PN 1
J 2
(-2060 -415);
DISPLAY 0.680851 (-2060 -415);
PAINT MONO (-2060 -415);
FORCEPROP 0 LASTPIN (-2050 -475) $PN 6
J 2
(-2060 -465);
DISPLAY 0.680851 (-2060 -465);
PAINT MONO (-2060 -465);
FORCEPROP 0 LASTPIN (-2050 -525) $PN 10
J 2
(-2060 -515);
DISPLAY 0.680851 (-2060 -515);
PAINT MONO (-2060 -515);
FORCEPROP 0 LAST CDS_LOCATION U22
J 0
(-1900 0);
DISPLAY 0.680851 (-1900 0);
DISPLAY INVISIBLE (-1900 0);
FORCEPROP 0 LAST $SEC 1
J 0
(-1900 0);
DISPLAY 0.680851 (-1900 0);
PAINT MONO (-1900 0);
DISPLAY INVISIBLE (-1900 0);
FORCEPROP 0 LAST CDS_SEC 1
J 0
(-1900 0);
DISPLAY 0.680851 (-1900 0);
DISPLAY INVISIBLE (-1900 0);
FORCEADD OFFPAGE..5
(-2875 -675);
FORCEPROP 2 LAST $XR0 29 
J 0
(-3099 -675);
DISPLAY 0.638298 (-3099 -675);
PAINT MONO (-3099 -675);
FORCEPROP 1 LAST OFFPAGE TRUE
J 0
(-2550 -800);
DISPLAY 0.872340 (-2550 -800);
DISPLAY INVISIBLE (-2550 -800);
FORCEPROP 1 LAST COMMENT_BODY TRUE
J 0
(-2775 -750);
DISPLAY 0.872340 (-2775 -750);
PAINT GREEN (-2775 -750);
DISPLAY INVISIBLE (-2775 -750);
FORCEPROP 2 LAST PATH I207
J 0
(-2825 -600);
DISPLAY 0.680851 (-2825 -600);
DISPLAY INVISIBLE (-2825 -600);
FORCEPROP 2 LAST CDS_LIB standard
J 0
(-2875 -675);
DISPLAY INVISIBLE (-2875 -675);
FORCEADD OFFPAGE..5
(-2875 -725);
FORCEPROP 2 LAST $XR0 29 
J 0
(-3099 -725);
DISPLAY 0.638298 (-3099 -725);
PAINT MONO (-3099 -725);
FORCEPROP 1 LAST OFFPAGE TRUE
J 0
(-2550 -850);
DISPLAY 0.872340 (-2550 -850);
DISPLAY INVISIBLE (-2550 -850);
FORCEPROP 1 LAST COMMENT_BODY TRUE
J 0
(-2775 -800);
DISPLAY 0.872340 (-2775 -800);
PAINT GREEN (-2775 -800);
DISPLAY INVISIBLE (-2775 -800);
FORCEPROP 2 LAST PATH I208
J 0
(-2825 -650);
DISPLAY 0.680851 (-2825 -650);
DISPLAY INVISIBLE (-2825 -650);
FORCEPROP 2 LAST CDS_LIB standard
J 0
(-2875 -725);
DISPLAY INVISIBLE (-2875 -725);
FORCEADD OFFPAGE..4
R 2
(-2875 -775);
FORCEPROP 2 LAST $XR0 29 
J 0
(-3096 -775);
DISPLAY 0.638298 (-3096 -775);
PAINT MONO (-3096 -775);
FORCEPROP 2 LAST CDS_LIB standard
J 0
(-2875 -775);
DISPLAY INVISIBLE (-2875 -775);
FORCEPROP 2 LAST PATH I209
J 0
(-2825 -700);
DISPLAY 0.680851 (-2825 -700);
DISPLAY INVISIBLE (-2825 -700);
FORCEPROP 1 LAST OFFPAGE TRUE
J 2
(-3200 -900);
DISPLAY 0.872340 (-3200 -900);
PAINT GREEN (-3200 -900);
DISPLAY INVISIBLE (-3200 -900);
FORCEPROP 1 LAST COMMENT_BODY TRUE
J 2
(-2850 -875);
DISPLAY 0.872340 (-2850 -875);
PAINT PEACH (-2850 -875);
DISPLAY INVISIBLE (-2850 -875);
FORCEADD OFFPAGE..4
R 2
(-2875 -825);
FORCEPROP 2 LAST $XR0 29 
J 0
(-3100 -825);
DISPLAY 0.638298 (-3100 -825);
PAINT MONO (-3100 -825);
FORCEPROP 2 LAST CDS_LIB standard
J 0
(-2875 -825);
DISPLAY INVISIBLE (-2875 -825);
FORCEPROP 2 LAST PATH I210
J 0
(-2825 -750);
DISPLAY 0.680851 (-2825 -750);
DISPLAY INVISIBLE (-2825 -750);
FORCEPROP 1 LAST OFFPAGE TRUE
J 2
(-3200 -950);
DISPLAY 0.872340 (-3200 -950);
PAINT GREEN (-3200 -950);
DISPLAY INVISIBLE (-3200 -950);
FORCEPROP 1 LAST COMMENT_BODY TRUE
J 2
(-2850 -925);
DISPLAY 0.872340 (-2850 -925);
PAINT PEACH (-2850 -925);
DISPLAY INVISIBLE (-2850 -925);
FORCEADD DT1240E04LP7..1
(-2400 3050);
FORCEPROP 2 LAST VALUE DT1240E-04LP-7
J 0
(-2600 3600);
DISPLAY 0.680851 (-2600 3600);
FORCEPROP 2 LAST PART_TYPE SMLF
J 0
(-2600 3650);
DISPLAY 0.680851 (-2600 3650);
FORCEPROP 1 LAST MATERIAL IC
J 0
(-2645 3457);
DISPLAY 0.723404 (-2645 3457);
PAINT GREEN (-2645 3457);
FORCEPROP 1 LAST PART_NUMBER BC001240Z01
J 0
(-2615 3515);
DISPLAY 0.723404 (-2615 3515);
PAINT GREEN (-2615 3515);
FORCEPROP 2 LAST SEC_TYPE 
J 0
(-2600 3700);
DISPLAY 0.680851 (-2600 3700);
DISPLAY INVISIBLE (-2600 3700);
FORCEPROP 2 LAST CDS_LIB pure_quanta
J 0
(-2400 3050);
DISPLAY INVISIBLE (-2400 3050);
FORCEPROP 1 LAST PATH I211
J 0
(-2400 3050);
DISPLAY 0.723404 (-2400 3050);
PAINT GREEN (-2400 3050);
DISPLAY INVISIBLE (-2400 3050);
FORCEPROP 1 LAST NEEDS_NO_SIZE TRUE
J 0
(-2400 3050);
DISPLAY 0.723404 (-2400 3050);
PAINT GREEN (-2400 3050);
DISPLAY INVISIBLE (-2400 3050);
FORCEPROP 1 LAST CDS_LMAN_SYM_OUTLINE -250,400,250,-400
J 0
(-2400 3050);
DISPLAY 0.468085 (-2400 3050);
PAINT GREEN (-2400 3050);
DISPLAY INVISIBLE (-2400 3050);
FORCEPROP 1 LAST LOCATION U27
J 0
(-2620 3556);
DISPLAY 0.723404 (-2620 3556);
PAINT GREEN (-2620 3556);
FORCEPROP 2 LASTPIN (-2800 3350) $PN 1
J 2
(-2810 3360);
DISPLAY 0.680851 (-2810 3360);
PAINT MONO (-2810 3360);
FORCEPROP 2 LASTPIN (-2800 3200) $PN 2
J 2
(-2810 3210);
DISPLAY 0.680851 (-2810 3210);
PAINT MONO (-2810 3210);
FORCEPROP 2 LASTPIN (-2800 3050) $PN 4
J 2
(-2810 3060);
DISPLAY 0.680851 (-2810 3060);
PAINT MONO (-2810 3060);
FORCEPROP 2 LASTPIN (-2800 2900) $PN 5
J 2
(-2810 2910);
DISPLAY 0.680851 (-2810 2910);
PAINT MONO (-2810 2910);
FORCEPROP 2 LASTPIN (-2000 2850) $PN 6
J 0
(-1990 2860);
DISPLAY 0.680851 (-1990 2860);
PAINT MONO (-1990 2860);
FORCEPROP 2 LASTPIN (-2000 2800) $PN 7
J 0
(-1990 2810);
DISPLAY 0.680851 (-1990 2810);
PAINT MONO (-1990 2810);
FORCEPROP 2 LASTPIN (-2000 2750) $PN 9
J 0
(-1990 2760);
DISPLAY 0.680851 (-1990 2760);
PAINT MONO (-1990 2760);
FORCEPROP 2 LASTPIN (-2000 2700) $PN 10
J 0
(-1990 2710);
DISPLAY 0.680851 (-1990 2710);
PAINT MONO (-1990 2710);
FORCEPROP 2 LASTPIN (-2000 3350) $PN 3
J 0
(-1990 3360);
DISPLAY 0.680851 (-1990 3360);
PAINT MONO (-1990 3360);
FORCEPROP 2 LASTPIN (-2000 3200) $PN 8
J 0
(-1990 3210);
DISPLAY 0.680851 (-1990 3210);
PAINT MONO (-1990 3210);
FORCEPROP 2 LAST SEC 1
J 0
(-2600 3700);
DISPLAY 0.680851 (-2600 3700);
PAINT MONO (-2600 3700);
DISPLAY INVISIBLE (-2600 3700);
FORCEADD UNIVERSAL_GND..1
R 2
(-1925 3100);
FORCEPROP 3 LASTPIN (-1925 3150) SIG_NAME GND\g
J 0
(-1915 3160);
DISPLAY 0.659574 (-1915 3160);
PAINT MONO (-1915 3160);
DISPLAY INVISIBLE (-1915 3160);
FORCEPROP 1 LAST HDL_POWER GND
J 1
(-1950 3025);
DISPLAY 0.702128 (-1950 3025);
PAINT GREEN (-1950 3025);
FORCEPROP 2 LAST CDS_LIB logical_power
J 0
(-1925 3100);
DISPLAY INVISIBLE (-1925 3100);
FORCEPROP 1 LAST PATH I212
J 2
(-2000 3100);
DISPLAY 0.872340 (-2000 3100);
PAINT AQUA (-2000 3100);
DISPLAY INVISIBLE (-2000 3100);
FORCEADD OFFPAGE..5
R 2
(325 -525);
FORCEPROP 2 LAST $XR0 10 
J 0
(514 -525);
DISPLAY 0.638298 (514 -525);
PAINT MONO (514 -525);
FORCEPROP 2 LAST CDS_LIB standard
J 2
(325 -525);
DISPLAY INVISIBLE (325 -525);
FORCEPROP 1 LAST OFFPAGE TRUE
J 2
(0 -650);
DISPLAY 0.872340 (0 -650);
DISPLAY INVISIBLE (0 -650);
FORCEPROP 1 LAST COMMENT_BODY TRUE
J 2
(225 -600);
DISPLAY 0.872340 (225 -600);
PAINT GREEN (225 -600);
DISPLAY INVISIBLE (225 -600);
FORCEPROP 2 LAST PATH I217
J 0
(525 -475);
DISPLAY 0.680851 (525 -475);
DISPLAY INVISIBLE (525 -475);
FORCEADD OFFPAGE..5
R 2
(325 -575);
FORCEPROP 2 LAST $XR0 10 
J 0
(514 -575);
DISPLAY 0.638298 (514 -575);
PAINT MONO (514 -575);
FORCEPROP 2 LAST CDS_LIB standard
J 2
(325 -575);
DISPLAY INVISIBLE (325 -575);
FORCEPROP 1 LAST OFFPAGE TRUE
J 2
(0 -700);
DISPLAY 0.872340 (0 -700);
DISPLAY INVISIBLE (0 -700);
FORCEPROP 1 LAST COMMENT_BODY TRUE
J 2
(225 -650);
DISPLAY 0.872340 (225 -650);
PAINT GREEN (225 -650);
DISPLAY INVISIBLE (225 -650);
FORCEPROP 2 LAST PATH I218
J 0
(525 -525);
DISPLAY 0.680851 (525 -525);
DISPLAY INVISIBLE (525 -525);
FORCEADD Q_CAP..1
(825 1450);
FORCEPROP 1 LAST VALUE 47UF
J 0
(875 1500);
DISPLAY 0.638298 (875 1500);
FORCEPROP 1 LAST VOLTAGE 6.3V
J 0
(875 1450);
DISPLAY 0.638298 (875 1450);
FORCEPROP 1 LAST PACK_TYPE C1206
J 0
(875 1250);
DISPLAY 0.638298 (875 1250);
FORCEPROP 1 LAST TOLERANCE 20%
J 0
(875 1400);
DISPLAY 0.638298 (875 1400);
FORCEPROP 1 LAST PART_NUMBER CH6471ME200
J 0
(875 1300);
DISPLAY 0.638298 (875 1300);
FORCEPROP 1 LAST MATERIAL X6S
J 0
(875 1350);
DISPLAY 0.638298 (875 1350);
FORCEPROP 2 LAST CDS_LIB pure_quanta
J 0
(825 1450);
DISPLAY INVISIBLE (825 1450);
FORCEPROP 1 LAST PATH I219
J 0
(875 1600);
DISPLAY 0.978723 (875 1600);
PAINT WHITE (875 1600);
DISPLAY INVISIBLE (875 1600);
FORCEPROP 1 LAST LOCATION C177
J 0
(875 1550);
DISPLAY 0.638298 (875 1550);
FORCEPROP 1 LASTPIN (825 1550) $PN 1
J 0
(835 1530);
DISPLAY 0.787234 (835 1530);
PAINT MONO (835 1530);
FORCEPROP 1 LASTPIN (825 1350) $PN 2
J 0
(835 1330);
DISPLAY 0.787234 (835 1330);
PAINT MONO (835 1330);
FORCEPROP 0 LAST $SEC 1
J 0
(875 1600);
DISPLAY 0.680851 (875 1600);
PAINT MONO (875 1600);
DISPLAY INVISIBLE (875 1600);
FORCEPROP 0 LAST CDS_SEC 1
J 0
(875 1600);
DISPLAY 0.680851 (875 1600);
DISPLAY INVISIBLE (875 1600);
FORCEADD Q_CAP..1
(1150 1450);
FORCEPROP 1 LAST VOLTAGE 6.3V
J 0
(1200 1450);
DISPLAY 0.638298 (1200 1450);
FORCEPROP 1 LAST TOLERANCE 20%
J 0
(1200 1400);
DISPLAY 0.638298 (1200 1400);
FORCEPROP 1 LAST MATERIAL X6S
J 0
(1200 1350);
DISPLAY 0.638298 (1200 1350);
FORCEPROP 1 LAST PACK_TYPE C1206
J 0
(1200 1250);
DISPLAY 0.638298 (1200 1250);
FORCEPROP 1 LAST PART_NUMBER CH6471ME200
J 0
(1200 1300);
DISPLAY 0.638298 (1200 1300);
FORCEPROP 1 LAST VALUE 47UF
J 0
(1200 1500);
DISPLAY 0.638298 (1200 1500);
FORCEPROP 1 LAST PATH I220
J 0
(1200 1600);
DISPLAY 0.978723 (1200 1600);
PAINT WHITE (1200 1600);
DISPLAY INVISIBLE (1200 1600);
FORCEPROP 2 LAST CDS_LIB pure_quanta
J 0
(1150 1450);
DISPLAY INVISIBLE (1150 1450);
FORCEPROP 1 LAST LOCATION C327
J 0
(1200 1550);
DISPLAY 0.638298 (1200 1550);
FORCEPROP 1 LASTPIN (1150 1550) $PN 1
J 0
(1160 1530);
DISPLAY 0.787234 (1160 1530);
PAINT MONO (1160 1530);
FORCEPROP 1 LASTPIN (1150 1350) $PN 2
J 0
(1160 1330);
DISPLAY 0.787234 (1160 1330);
PAINT MONO (1160 1330);
FORCEPROP 0 LAST $SEC 1
J 0
(1200 1600);
DISPLAY 0.680851 (1200 1600);
PAINT MONO (1200 1600);
DISPLAY INVISIBLE (1200 1600);
FORCEPROP 0 LAST CDS_SEC 1
J 0
(1200 1600);
DISPLAY 0.680851 (1200 1600);
DISPLAY INVISIBLE (1200 1600);
FORCEADD CONN9_GSB3111315HR..1
(4375 525);
FORCEPROP 2 LAST PART_TYPE THLF
J 0
(4125 1200);
DISPLAY 0.680851 (4125 1200);
FORCEPROP 1 LAST MATERIAL IO
J 0
(4105 832);
DISPLAY 0.723404 (4105 832);
PAINT GREEN (4105 832);
FORCEPROP 2 LAST VALUE CONN9_GSB3111315HR
J 0
(4125 1150);
DISPLAY 0.680851 (4125 1150);
FORCEPROP 1 LAST PART_NUMBER DFHS09FR401
J 0
(4105 959);
DISPLAY 0.723404 (4105 959);
PAINT GREEN (4105 959);
FORCEPROP 2 LAST CDS_LIB pure_quanta
J 0
(4375 525);
DISPLAY INVISIBLE (4375 525);
FORCEPROP 1 LAST PATH I221
J 0
(4375 525);
DISPLAY 0.723404 (4375 525);
PAINT GREEN (4375 525);
DISPLAY INVISIBLE (4375 525);
FORCEPROP 1 LAST NEEDS_NO_SIZE TRUE
J 0
(4375 525);
DISPLAY 0.723404 (4375 525);
PAINT GREEN (4375 525);
DISPLAY INVISIBLE (4375 525);
FORCEPROP 1 LAST CDS_LMAN_SYM_OUTLINE -275,300,275,-300
J 0
(4375 525);
DISPLAY 0.468085 (4375 525);
PAINT GREEN (4375 525);
DISPLAY INVISIBLE (4375 525);
FORCEPROP 1 LAST LOCATION J2
J 0
(4105 1106);
DISPLAY 0.723404 (4105 1106);
PAINT GREEN (4105 1106);
FORCEPROP 0 LASTPIN (3950 475) $PN 3
J 2
(3940 485);
DISPLAY 0.680851 (3940 485);
PAINT MONO (3940 485);
FORCEPROP 0 LASTPIN (3950 575) $PN 2
J 2
(3940 585);
DISPLAY 0.680851 (3940 585);
PAINT MONO (3940 585);
FORCEPROP 0 LASTPIN (4800 375) $PN G1
J 0
(4810 385);
DISPLAY 0.680851 (4810 385);
PAINT MONO (4810 385);
FORCEPROP 0 LASTPIN (4800 325) $PN G2
J 0
(4810 335);
DISPLAY 0.680851 (4810 335);
PAINT MONO (4810 335);
FORCEPROP 0 LASTPIN (3950 525) $PN 4
J 2
(3940 535);
DISPLAY 0.680851 (3940 535);
PAINT MONO (3940 535);
FORCEPROP 0 LASTPIN (3950 375) $PN 7
J 2
(3940 385);
DISPLAY 0.680851 (3940 385);
PAINT MONO (3940 385);
FORCEPROP 0 LASTPIN (3950 425) $PN 6
J 2
(3940 435);
DISPLAY 0.680851 (3940 435);
PAINT MONO (3940 435);
FORCEPROP 0 LASTPIN (3950 325) $PN 5
J 2
(3940 335);
DISPLAY 0.680851 (3940 335);
PAINT MONO (3940 335);
FORCEPROP 0 LASTPIN (3950 725) $PN 9
J 2
(3940 735);
DISPLAY 0.680851 (3940 735);
PAINT MONO (3940 735);
FORCEPROP 0 LASTPIN (3950 625) $PN 8
J 2
(3940 635);
DISPLAY 0.680851 (3940 635);
PAINT MONO (3940 635);
FORCEPROP 0 LASTPIN (3950 675) $PN 1
J 2
(3940 685);
DISPLAY 0.680851 (3940 685);
PAINT MONO (3940 685);
FORCEPROP 0 LAST $SEC 1
J 0
(4125 1250);
DISPLAY 0.680851 (4125 1250);
PAINT MONO (4125 1250);
DISPLAY INVISIBLE (4125 1250);
FORCEPROP 0 LAST CDS_SEC 1
J 0
(4125 1250);
DISPLAY 0.680851 (4125 1250);
DISPLAY INVISIBLE (4125 1250);
FORCEADD Q_RES..1
(2050 375);
FORCEPROP 1 LAST MATERIAL CHIP
J 2
(2325 375);
DISPLAY 0.510638 (2325 375);
PAINT SKYBLUE (2325 375);
FORCEPROP 1 LAST VALUE 33.2
J 0
(2125 375);
DISPLAY 0.510638 (2125 375);
PAINT SKYBLUE (2125 375);
FORCEPROP 1 LAST TOLERANCE 1%
J 0
(2175 375);
DISPLAY 0.510638 (2175 375);
PAINT SKYBLUE (2175 375);
DISPLAY INVISIBLE (2175 375);
FORCEPROP 1 LAST PART_NUMBER CS03322FB03
J 0
(2000 475);
DISPLAY 0.510638 (2000 475);
PAINT WHITE (2000 475);
DISPLAY INVISIBLE (2000 475);
FORCEPROP 1 LAST PACK_TYPE 0402LF
J 0
(2300 225);
DISPLAY 0.510638 (2300 225);
PAINT SKYBLUE (2300 225);
DISPLAY INVISIBLE (2300 225);
FORCEPROP 1 LAST WATTAGE 1/16W
J 2
(2025 225);
DISPLAY 0.510638 (2025 225);
PAINT SKYBLUE (2025 225);
DISPLAY INVISIBLE (2025 225);
FORCEPROP 1 LAST PATH I222
J 0
(2000 525);
DISPLAY 0.978723 (2000 525);
PAINT WHITE (2000 525);
DISPLAY INVISIBLE (2000 525);
FORCEPROP 2 LAST CDS_LIB pure_quanta
J 0
(2050 375);
DISPLAY INVISIBLE (2050 375);
FORCEPROP 1 LAST LOCATION R693
J 2
(2000 375);
DISPLAY 0.702128 (2000 375);
PAINT YELLOW (2000 375);
FORCEPROP 1 LASTPIN (1950 375) $PN 1
J 0
(1962 387);
DISPLAY 0.787234 (1962 387);
PAINT MONO (1962 387);
FORCEPROP 1 LASTPIN (2150 375) $PN 2
J 0
(2112 387);
DISPLAY 0.787234 (2112 387);
PAINT MONO (2112 387);
FORCEPROP 0 LAST $SEC 1
J 0
(2000 425);
DISPLAY 0.680851 (2000 425);
PAINT MONO (2000 425);
DISPLAY INVISIBLE (2000 425);
FORCEPROP 0 LAST CDS_SEC 1
J 0
(2000 425);
DISPLAY 0.680851 (2000 425);
DISPLAY INVISIBLE (2000 425);
FORCEADD UNIVERSAL_POWER..1
(-275 1425);
FORCEPROP 3 LASTPIN (-275 1375) SIG_NAME P5V_USB_REAR\g
J 0
(-265 1385);
DISPLAY 0.659574 (-265 1385);
PAINT MONO (-265 1385);
DISPLAY INVISIBLE (-265 1385);
FORCEPROP 1 LAST HDL_POWER P5V_USB_REAR
J 1
(-275 1475);
DISPLAY 0.702128 (-275 1475);
PAINT GREEN (-275 1475);
FORCEPROP 1 LAST PATH I95
J 0
(-225 1450);
DISPLAY 0.872340 (-225 1450);
PAINT AQUA (-225 1450);
DISPLAY INVISIBLE (-225 1450);
FORCEPROP 2 LAST CDS_LIB logical_power
J 0
(-275 1425);
PAINT RED (-275 1425);
DISPLAY INVISIBLE (-275 1425);
FORCEADD Q_RES..1
(-2450 2050);
FORCEPROP 1 LAST WATTAGE 1/16W
J 2
(-2475 1950);
DISPLAY 0.510638 (-2475 1950);
PAINT SKYBLUE (-2475 1950);
FORCEPROP 1 LAST VALUE 0
J 2
(-2475 2000);
DISPLAY 0.510638 (-2475 2000);
PAINT SKYBLUE (-2475 2000);
FORCEPROP 1 LAST PACK_TYPE 0402LF
J 0
(-2250 1950);
DISPLAY 0.510638 (-2250 1950);
PAINT SKYBLUE (-2250 1950);
FORCEPROP 1 LAST TOLERANCE 5%
J 0
(-2450 2000);
DISPLAY 0.510638 (-2450 2000);
PAINT SKYBLUE (-2450 2000);
FORCEPROP 1 LAST MATERIAL CHIP
J 0
(-2450 1950);
DISPLAY 0.510638 (-2450 1950);
PAINT SKYBLUE (-2450 1950);
FORCEPROP 1 LAST PART_NUMBER CS00002JB13
J 0
(-2500 2150);
DISPLAY 0.510638 (-2500 2150);
PAINT WHITE (-2500 2150);
FORCEPROP 1 LAST PATH I96
J 0
(-2500 2200);
DISPLAY 0.978723 (-2500 2200);
PAINT WHITE (-2500 2200);
DISPLAY INVISIBLE (-2500 2200);
FORCEPROP 2 LAST CDS_LIB pure_quanta
J 0
(-2450 2050);
PAINT RED (-2450 2050);
DISPLAY INVISIBLE (-2450 2050);
FORCEPROP 1 LAST LOCATION R385
J 0
(-2500 2100);
DISPLAY 0.702128 (-2500 2100);
PAINT YELLOW (-2500 2100);
FORCEPROP 1 LASTPIN (-2550 2050) $PN 1
J 0
(-2538 2062);
DISPLAY 0.808511 (-2538 2062);
PAINT WHITE (-2538 2062);
FORCEPROP 1 LASTPIN (-2350 2050) $PN 2
J 0
(-2388 2062);
DISPLAY 0.808511 (-2388 2062);
PAINT WHITE (-2388 2062);
FORCEPROP 2 LAST $SEC 1
J 0
(-2500 2250);
DISPLAY 0.680851 (-2500 2250);
PAINT MONO (-2500 2250);
DISPLAY INVISIBLE (-2500 2250);
FORCEPROP 2 LAST CDS_SEC 1
J 0
(-2500 2250);
DISPLAY 1.021277 (-2500 2250);
DISPLAY INVISIBLE (-2500 2250);
FORCEADD OFFPAGE..3
(-950 1800);
FORCEPROP 2 LAST $XR0 29 
J 0
(-736 1800);
DISPLAY 0.638298 (-736 1800);
PAINT MONO (-736 1800);
FORCEPROP 2 LAST PATH I97
J 0
(-725 1850);
DISPLAY 0.680851 (-725 1850);
DISPLAY INVISIBLE (-725 1850);
FORCEPROP 1 LAST COMMENT_BODY TRUE
J 0
(-1000 1700);
DISPLAY 0.872340 (-1000 1700);
PAINT PEACH (-1000 1700);
DISPLAY INVISIBLE (-1000 1700);
FORCEPROP 1 LAST OFFPAGE TRUE
J 0
(-625 1675);
DISPLAY 0.872340 (-625 1675);
PAINT GREEN (-625 1675);
DISPLAY INVISIBLE (-625 1675);
FORCEPROP 2 LAST CDS_LIB standard
J 0
(-950 1800);
PAINT MONO (-950 1800);
DISPLAY INVISIBLE (-950 1800);
FORCEADD OFFPAGE..3
(-950 1550);
FORCEPROP 2 LAST $XR0 29 
J 0
(-736 1550);
DISPLAY 0.638298 (-736 1550);
PAINT MONO (-736 1550);
FORCEPROP 2 LAST PATH I98
J 0
(-725 1600);
DISPLAY 0.680851 (-725 1600);
DISPLAY INVISIBLE (-725 1600);
FORCEPROP 1 LAST COMMENT_BODY TRUE
J 0
(-1000 1450);
DISPLAY 0.872340 (-1000 1450);
PAINT PEACH (-1000 1450);
DISPLAY INVISIBLE (-1000 1450);
FORCEPROP 1 LAST OFFPAGE TRUE
J 0
(-625 1425);
DISPLAY 0.872340 (-625 1425);
PAINT GREEN (-625 1425);
DISPLAY INVISIBLE (-625 1425);
FORCEPROP 2 LAST CDS_LIB standard
J 0
(-950 1550);
PAINT MONO (-950 1550);
DISPLAY INVISIBLE (-950 1550);
FORCEADD PRTR5V0U2X..1
(-725 1075);
FORCEPROP 2 LAST VALUE PRTR5V0U2X
J 0
(-900 1400);
DISPLAY 0.510638 (-900 1400);
PAINT SKYBLUE (-900 1400);
FORCEPROP 1 LAST PART_NUMBER AL5V0U2X000
J 0
(-903 1282);
DISPLAY 0.510638 (-903 1282);
PAINT WHITE (-903 1282);
FORCEPROP 1 LAST MATERIAL IC
J 0
(-903 1213);
DISPLAY 0.510638 (-903 1213);
PAINT SKYBLUE (-903 1213);
FORCEPROP 2 LAST PART_TYPE SMLF
J 0
(-900 1450);
DISPLAY 0.510638 (-900 1450);
PAINT SKYBLUE (-900 1450);
FORCEPROP 1 LAST PATH I99
J 0
(-550 950);
DISPLAY 0.723404 (-550 950);
PAINT GREEN (-550 950);
DISPLAY INVISIBLE (-550 950);
FORCEPROP 2 LAST CDS_LIB pure_quanta
J 0
(-725 1075);
DISPLAY INVISIBLE (-725 1075);
FORCEPROP 1 LAST CDS_LMAN_SYM_OUTLINE -175,125,175,-125
J 0
(-725 1075);
DISPLAY 0.468085 (-725 1075);
PAINT GREEN (-725 1075);
DISPLAY INVISIBLE (-725 1075);
FORCEPROP 1 LAST NEEDS_NO_SIZE TRUE
J 0
(-550 990);
DISPLAY 0.723404 (-550 990);
PAINT GREEN (-550 990);
DISPLAY INVISIBLE (-550 990);
FORCEPROP 1 LAST LOCATION U38
J 0
(-903 1346);
DISPLAY 0.702128 (-903 1346);
PAINT YELLOW (-903 1346);
FORCEPROP 0 LASTPIN (-1050 1000) $PN 1
J 2
(-1060 1010);
DISPLAY 0.680851 (-1060 1010);
PAINT MONO (-1060 1010);
FORCEPROP 0 LASTPIN (-1050 1150) $PN 2
J 2
(-1060 1160);
DISPLAY 0.680851 (-1060 1160);
PAINT MONO (-1060 1160);
FORCEPROP 0 LASTPIN (-400 1000) $PN 3
J 0
(-390 1010);
DISPLAY 0.680851 (-390 1010);
PAINT MONO (-390 1010);
FORCEPROP 0 LASTPIN (-400 1150) $PN 4
J 0
(-390 1160);
DISPLAY 0.680851 (-390 1160);
PAINT MONO (-390 1160);
FORCEPROP 0 LAST $SEC 1
J 0
(-900 1475);
DISPLAY 0.680851 (-900 1475);
PAINT MONO (-900 1475);
DISPLAY INVISIBLE (-900 1475);
FORCEPROP 0 LAST CDS_SEC 1
J 0
(-900 1475);
DISPLAY 1.021277 (-900 1475);
DISPLAY INVISIBLE (-900 1475);
FORCEADD QUANTA_TITLE_BLOCK_C..1
(5125 -2225);
FORCEPROP 0 LAST CDS_CON_LAST_MODIFIED Fri Aug 25 17:25:42 2023
J 0
(3240 -2210);
DISPLAY INVISIBLE (3240 -2210);
FORCEPROP 2 LAST Q_DEPT 
J 1
(1362 -2176);
DISPLAY 1.957447 (1362 -2176);
PAINT GREEN (1362 -2176);
FORCEPROP 1 LAST CUSTOM_TXT_CDS <CON_LAST_MODIFIED>
J 0
(3240 -2210);
DISPLAY 0.978723 (3240 -2210);
FORCEPROP 2 LAST CUSTOM_TXT_CDS <XR_PAGE_TITLE>
J 0
(-2765 3025);
DISPLAY 0.638298 (-2765 3025);
PAINT PINK (-2765 3025);
DISPLAY INVISIBLE (-2765 3025);
FORCEPROP 1 LAST CUSTOM_TXT_CDS <NAME_2>
J 0
(1950 -2175);
FORCEPROP 1 LAST CUSTOM_TXT_CDS <NAME_1>
J 0
(1950 -2050);
FORCEPROP 1 LAST CUSTOM_TXT_CDS <Q_NUMBER>
J 0
(3722 -2122);
DISPLAY 1.212766 (3722 -2122);
FORCEPROP 1 LAST CUSTOM_TXT_CDS <Q_PROJ>
J 0
(2743 -2123);
DISPLAY 1.212766 (2743 -2123);
FORCEPROP 1 LAST CUSTOM_TXT_CDS <Q_REV>
J 0
(4941 -2122);
DISPLAY 1.212766 (4941 -2122);
FORCEPROP 1 LAST CUSTOM_TXT_CDS <CON_PAGE_NUM> OF <CON_TOTAL_PAGES>
J 0
(4679 -2207);
DISPLAY 0.978723 (4679 -2207);
FORCEPROP 1 LAST Q_TITLE USB - DEBUG CONNECTOR 2/2
J 0
(-4216 -2199);
DISPLAY 2.446809 (-4216 -2199);
PAINT GREEN (-4216 -2199);
FORCEPROP 2 LAST CDS_LIB pure_quanta
J 0
(5125 -2225);
DISPLAY INVISIBLE (5125 -2225);
FORCEPROP 1 LAST CDS_LMAN_SYM_OUTLINE -9475,6775,100,-125
J 0
(5125 -2225);
DISPLAY 0.468085 (5125 -2225);
PAINT GREEN (5125 -2225);
DISPLAY INVISIBLE (5125 -2225);
FORCEPROP 2 LAST PAGE_BORDER TRUE
J 0
(-2765 3025);
DISPLAY 0.638298 (-2765 3025);
PAINT PINK (-2765 3025);
DISPLAY INVISIBLE (-2765 3025);
FORCEPROP 1 LAST COMMENT_BODY TRUE
J 0
(5137 -2238);
DISPLAY 0.978723 (5137 -2238);
PAINT PEACH (5137 -2238);
DISPLAY INVISIBLE (5137 -2238);
FORCEPROP 2 LAST CDS_XR_PAGE_TITLE CR-29 : @SCM_LIB.SCM(SCH_1):PAGE29
J 0
(-2765 3025);
DISPLAY 0.638298 (-2765 3025);
PAINT PINK (-2765 3025);
DISPLAY INVISIBLE (-2765 3025);
FORCEADD DNS..1
(-50 75);
PAINT RED (-50 75);
FORCEPROP 1 LAST COMMENT_BODY TRUE
R 1
J 0
(25 -150);
DISPLAY 0.872340 (25 -150);
PAINT PEACH (25 -150);
DISPLAY INVISIBLE (25 -150);
FORCEPROP 2 LAST CDS_LIB mstr_misc
J 0
(-50 75);
DISPLAY INVISIBLE (-50 75);
FORCEADD DNS..1
(-25 225);
PAINT RED (-25 225);
FORCEPROP 1 LAST COMMENT_BODY TRUE
R 1
J 0
(50 0);
DISPLAY 0.872340 (50 0);
PAINT PEACH (50 0);
DISPLAY INVISIBLE (50 0);
FORCEPROP 2 LAST CDS_LIB mstr_misc
J 0
(-25 225);
DISPLAY INVISIBLE (-25 225);
FORCEADD DNS..5
(-2425 1650);
PAINT RED (-2425 1650);
FORCEPROP 2 LAST CDS_LIB mstr_misc
J 0
(-2425 1650);
DISPLAY INVISIBLE (-2425 1650);
FORCEPROP 1 LAST COMMENT_BODY TRUE
R 1
J 0
(-2350 1425);
DISPLAY 0.872340 (-2350 1425);
PAINT PEACH (-2350 1425);
DISPLAY INVISIBLE (-2350 1425);
FORCEADD DNS..1
(4075 1950);
PAINT RED (4075 1950);
FORCEPROP 1 LAST COMMENT_BODY TRUE
R 1
J 0
(4150 1725);
DISPLAY 0.872340 (4150 1725);
PAINT PEACH (4150 1725);
DISPLAY INVISIBLE (4150 1725);
FORCEPROP 2 LAST CDS_LIB mstr_misc
J 0
(4075 1950);
DISPLAY INVISIBLE (4075 1950);
FORCEADD DNS..1
(4250 3800);
PAINT RED (4250 3800);
FORCEPROP 1 LAST COMMENT_BODY TRUE
R 1
J 0
(4325 3575);
DISPLAY 0.872340 (4325 3575);
PAINT PEACH (4325 3575);
DISPLAY INVISIBLE (4325 3575);
FORCEPROP 2 LAST CDS_LIB mstr_misc
J 0
(4250 3800);
DISPLAY INVISIBLE (4250 3800);
FORCEADD DNS..1
(-3625 -750);
PAINT RED (-3625 -750);
FORCEPROP 2 LAST CDS_LIB mstr_misc
J 0
(-3625 -750);
DISPLAY INVISIBLE (-3625 -750);
FORCEPROP 1 LAST COMMENT_BODY TRUE
R 1
J 0
(-3550 -975);
DISPLAY 0.872340 (-3550 -975);
PAINT PEACH (-3550 -975);
DISPLAY INVISIBLE (-3550 -975);
FORCEADD DNS..5
R 2
(-850 3850);
PAINT RED (-850 3850);
FORCEPROP 1 LAST COMMENT_BODY TRUE
R 1
J 0
(-884 3625);
DISPLAY 0.872340 (-884 3625);
PAINT PEACH (-884 3625);
DISPLAY INVISIBLE (-884 3625);
FORCEPROP 2 LAST CDS_LIB mstr_misc
J 2
(-850 3850);
DISPLAY INVISIBLE (-850 3850);
FORCEADD DNS..5
R 2
(-875 2525);
PAINT RED (-875 2525);
FORCEPROP 2 LAST CDS_LIB mstr_misc
J 2
(-875 2525);
DISPLAY INVISIBLE (-875 2525);
FORCEPROP 1 LAST COMMENT_BODY TRUE
R 1
J 0
(-909 2300);
DISPLAY 0.872340 (-909 2300);
PAINT PEACH (-909 2300);
DISPLAY INVISIBLE (-909 2300);
WIRE 16 -1 (825 1625)(825 1675);
WIRE 16 -1 (825 1625)(1150 1625);
WIRE 16 -1 (825 1625)(825 1550);
WIRE 16 -1 (4875 200)(4875 325);
WIRE 16 -1 (4650 -75)(4650 0);
WIRE 16 -1 (3875 675)(3875 1100);
WIRE 16 -1 (3875 675)(3950 675);
WIRE 16 -1 (2300 2175)(2300 1950);
WIRE 16 -1 (2475 2175)(2300 2175);
WIRE 16 -1 (3475 3700)(3475 3800);
WIRE 16 -1 (3225 3375)(3225 3325);
WIRE 16 -1 (3000 3375)(3225 3375);
WIRE 16 -1 (3775 25)(3775 -150);
WIRE 16 -1 (-3800 -625)(-3800 -425);
WIRE 16 -1 (-275 1375)(-275 1150);
WIRE 16 -1 (1750 1225)(1750 1125);
WIRE 16 -1 (1750 1225)(1750 1350);
WIRE 16 -1 (1400 1225)(1750 1225);
WIRE 16 -1 (-2150 525)(-2150 475);
WIRE 16 -1 (-1100 -1225)(-1100 -1425);
WIRE 16 -1 (-1100 -1225)(-1100 -1175);
WIRE 16 -1 (-1100 -1225)(-1300 -1225);
WIRE 16 -1 (2300 2925)(2300 2850);
WIRE 16 -1 (4225 3900)(4225 4125);
WIRE 16 -1 (3225 4150)(3225 4075);
WIRE 16 -1 (1275 3900)(1275 4125);
WIRE 16 -1 (4100 1875)(4100 1675);
WIRE 16 -1 (2050 2475)(2050 2575);
WIRE 16 -1 (3875 125)(3875 525);
WIRE 16 -1 (2475 -1750)(2475 -1800);
WIRE 16 -1 (2475 -1750)(2700 -1750);
WIRE 16 -1 (-2425 -25)(-2425 25);
WIRE 16 -1 (-3600 -1375)(-3600 -1525);
WIRE 16 -1 (-1925 3200)(-1925 3150);
WIRE 16 -1 (-1925 3350)(-1925 3200);
WIRE 16 -1 (-2000 3200)(-1925 3200);
WIRE 16 -1 (-1125 550)(-1125 1000);
WIRE 16 -1 (-1050 1000)(-1125 1000);
WIRE 16 -1 (-1100 -1125)(-1300 -1125);
WIRE 16 -1 (-1100 -1175)(-1300 -1175);
WIRE 16 -1 (-1100 -1175)(-1100 -1125);
WIRE 16 -1 (4800 325)(4875 325);
WIRE 16 -1 (4875 325)(4875 375);
WIRE 16 -1 (4800 375)(4875 375);
WIRE 16 -1 (3875 525)(3950 525);
WIRE 16 -1 (-400 1150)(-275 1150);
WIRE 16 -1 (1175 375)(1950 375);
FORCEPROP 2 LAST SIG_NAME DEBUG_PORT_PRSNT
J 0
(1190 385);
DISPLAY 0.851064 (1190 385);
WIRE 16 -1 (2475 425)(3950 425);
FORCEPROP 2 LAST SIG_NAME USB3_01_FB_RXP
J 0
(2515 435);
DISPLAY 0.808511 (2515 435);
WIRE 16 -1 (2150 375)(3775 375);
FORCEPROP 2 LAST SIG_NAME DEBUG_PORT_PRSNT_R
J 0
(2515 385);
DISPLAY 0.851064 (2515 385);
WIRE 16 -1 (3775 375)(3950 375);
WIRE 16 -1 (3775 225)(3775 375);
WIRE 16 -1 (2475 575)(3950 575);
FORCEPROP 2 LAST SIG_NAME USB2_01_F_DN
J 0
(2515 585);
DISPLAY 0.808511 (2515 585);
WIRE 16 -1 (2475 475)(3950 475);
FORCEPROP 2 LAST SIG_NAME USB2_01_F_DP
J 0
(2515 485);
DISPLAY 0.808511 (2515 485);
WIRE 16 -1 (2475 325)(3950 325);
FORCEPROP 2 LAST SIG_NAME USB3_01_FB_RXN
J 0
(2515 335);
DISPLAY 0.808511 (2515 335);
WIRE 16 -1 (50 225)(325 225);
WIRE 16 -1 (1075 225)(325 225);
FORCEPROP 2 LAST SIG_NAME USB3_FPNL_TXP
J 2
(1050 235);
DISPLAY 0.808511 (1050 235);
WIRE 16 -1 (325 500)(325 225);
WIRE 16 -1 (50 500)(325 500);
WIRE 16 273 (2150 950)(575 950);
WIRE 16 273 (2150 1875)(2150 950);
WIRE 16 273 (575 1875)(575 950);
WIRE 16 273 (575 1875)(2150 1875);
WIRE 16 -1 (825 1350)(825 1225);
WIRE 16 -1 (825 1225)(1150 1225);
WIRE 16 -1 (1150 1350)(1150 1225);
WIRE 16 -1 (1400 1225)(1150 1225);
WIRE 16 -1 (1400 1225)(1400 1350);
WIRE 16 -1 (4650 -450)(3675 -450);
FORCEPROP 2 LAST SIG_NAME FM_DEBUG_PORT_R_PRSNT_N
J 2
(4585 -440);
DISPLAY 0.851064 (4585 -440);
WIRE 16 -1 (4650 -275)(4650 -450);
WIRE 16 -1 (4650 -1250)(4650 -450);
WIRE 16 -1 (3600 -1250)(4650 -1250);
WIRE 16 -1 (1750 1625)(1750 1550);
WIRE 16 -1 (1400 1625)(1400 1550);
WIRE 16 -1 (1400 1625)(1750 1625);
WIRE 16 -1 (1150 1550)(1150 1625);
WIRE 16 -1 (1150 1625)(1400 1625);
WIRE 16 -1 (2475 625)(3950 625);
FORCEPROP 2 LAST SIG_NAME USB3_01_FB_TXN
J 0
(2515 635);
DISPLAY 0.808511 (2515 635);
WIRE 16 -1 (2475 725)(3950 725);
FORCEPROP 2 LAST SIG_NAME USB3_01_FB_TXP
J 0
(2515 735);
DISPLAY 0.808511 (2515 735);
WIRE 16 -1 (3475 -450)(2475 -450);
FORCEPROP 2 LAST SIG_NAME FM_DEBUG_PORT_PRSNT_N
J 2
(3335 -440);
DISPLAY 0.851064 (3335 -440);
WIRE 16 -1 (-1000 2925)(-1350 2925);
WIRE 16 -1 (-2000 2800)(-1575 2800);
WIRE 16 -1 (-1350 2625)(-1350 2925);
WIRE 16 -1 (-1350 2625)(-1275 2625);
WIRE 16 -1 (-1575 2625)(-1350 2625);
WIRE 16 -1 (-1575 2800)(-1575 2625);
WIRE 16 -1 (-3100 2625)(-1575 2625);
WIRE 16 -1 (-3850 2625)(-3100 2625);
FORCEPROP 2 LAST SIG_NAME USB3_01_FB_RXP
J 0
(-3825 2635);
DISPLAY 0.808511 (-3825 2635);
WIRE 16 -1 (-3100 3050)(-3100 2625);
WIRE 16 -1 (-2800 3050)(-3100 3050);
WIRE 16 -1 (-400 2400)(350 2400);
FORCEPROP 2 LAST SIG_NAME USB3_01_MUX_FB_RXN
J 0
(-335 2435);
DISPLAY 0.808511 (-335 2435);
WIRE 16 -1 (-400 2075)(-700 2075);
WIRE 16 -1 (-400 2400)(-400 2375);
WIRE 16 -1 (-400 2375)(-475 2375);
WIRE 16 -1 (-400 2375)(-400 2075);
WIRE 16 -1 (-2350 2050)(-1900 2050);
WIRE 16 -1 (-1900 1800)(-2000 1800);
WIRE 16 -1 (-1900 1800)(-1900 2050);
WIRE 16 -1 (-1775 1800)(-1900 1800);
WIRE 16 -1 (-1000 1800)(-1775 1800);
FORCEPROP 2 LAST SIG_NAME USB2_01_F_DN
J 0
(-1585 1810);
DISPLAY 0.808511 (-1585 1810);
WIRE 16 -1 (-1775 1800)(-1775 850);
WIRE 16 -1 (-300 850)(-1775 850);
WIRE 16 -1 (-300 1000)(-300 850);
WIRE 16 -1 (-400 1000)(-300 1000);
WIRE 16 -1 (-3050 1550)(-3475 1550);
FORCEPROP 2 LAST SIG_NAME USB_FPNL_DP
J 0
(-3460 1560);
DISPLAY 0.808511 (-3460 1560);
WIRE 16 -1 (-2800 1550)(-3050 1550);
WIRE 16 -1 (-3050 1550)(-3050 1115);
WIRE 16 -1 (-3050 1115)(-2350 1115);
WIRE 16 -1 (-2000 3350)(-1925 3350);
WIRE 16 -1 (-875 4250)(-1325 4250);
WIRE 16 -1 (-1750 2700)(-2000 2700);
WIRE 16 -1 (-1325 3950)(-1250 3950);
WIRE 16 -1 (-1325 3950)(-1325 4250);
WIRE 16 -1 (-1325 3950)(-1750 3950);
WIRE 16 -1 (-1750 3950)(-1750 2700);
WIRE 16 -1 (-3250 3950)(-1750 3950);
WIRE 16 -1 (-3875 3950)(-3250 3950);
FORCEPROP 2 LAST SIG_NAME USB3_01_FB_TXP
J 0
(-3850 3960);
DISPLAY 0.808511 (-3850 3960);
WIRE 16 -1 (-3250 3950)(-3250 3350);
WIRE 16 -1 (-3250 3350)(-2800 3350);
WIRE 16 -1 (-875 3400)(-1325 3400);
WIRE 16 -1 (-2000 2750)(-1650 2750);
WIRE 16 -1 (-1325 3700)(-1325 3400);
WIRE 16 -1 (-1250 3700)(-1325 3700);
WIRE 16 -1 (-1325 3700)(-1650 3700);
WIRE 16 -1 (-1650 2750)(-1650 3700);
WIRE 16 -1 (-3175 3700)(-3875 3700);
FORCEPROP 2 LAST SIG_NAME USB3_01_FB_TXN
J 0
(-3850 3710);
DISPLAY 0.808511 (-3850 3710);
WIRE 16 -1 (-3175 3700)(-1650 3700);
WIRE 16 -1 (-3175 3700)(-3175 3200);
WIRE 16 -1 (-3175 3200)(-2800 3200);
WIRE 16 -1 (-375 3400)(-675 3400);
WIRE 16 -1 (-375 3700)(-450 3700);
WIRE 16 -1 (-375 3700)(425 3700);
FORCEPROP 2 LAST SIG_NAME USB3_01_MUX_FB_TXN
J 0
(-260 3735);
DISPLAY 0.808511 (-260 3735);
WIRE 16 -1 (-375 3700)(-375 3400);
WIRE 16 -1 (1275 3700)(1275 3475);
WIRE 16 -1 (1275 3475)(2600 3475);
FORCEPROP 2 LAST SIG_NAME SPA_SIN_SW_DBG
J 0
(1640 3510);
DISPLAY 0.808511 (1640 3510);
WIRE 16 -1 (900 3475)(1275 3475);
WIRE 16 -1 (3475 4000)(3475 4075);
WIRE 16 -1 (3475 4075)(3225 4075);
WIRE 16 -1 (3225 4075)(3225 3575);
WIRE 16 -1 (3000 3575)(3225 3575);
WIRE 16 -1 (3100 3475)(4225 3475);
FORCEPROP 2 LAST SIG_NAME DEBUG_PORT_UART_RX
J 0
(3365 3485);
DISPLAY 0.851064 (3365 3485);
WIRE 16 -1 (4225 3475)(4425 3475);
WIRE 16 -1 (4225 3700)(4225 3475);
WIRE 16 -1 (2625 3075)(1925 3075);
FORCEPROP 2 LAST SIG_NAME DEBUG_PORT_PRSNT
J 0
(1940 3110);
DISPLAY 0.851064 (1940 3110);
WIRE 16 -1 (2625 2525)(2625 3075);
WIRE 16 -1 (2050 2775)(2050 2850);
WIRE 16 -1 (2050 2850)(2300 2850);
WIRE 16 -1 (2300 2850)(2300 2375);
WIRE 16 -1 (2475 2375)(2300 2375);
WIRE 16 -1 (4100 2275)(2875 2275);
FORCEPROP 2 LAST SIG_NAME DEBUG_PORT_UART_TX
J 0
(3290 2285);
DISPLAY 0.851064 (3290 2285);
WIRE 16 -1 (4100 2075)(4100 2275);
WIRE 16 -1 (4625 2275)(4100 2275);
WIRE 16 -1 (-1300 -825)(250 -825);
FORCEPROP 2 LAST SIG_NAME SMB_DEBUG_AUX_LVC3_USB_R2_SCL
J 0
(-1010 -815);
DISPLAY 0.851064 (-1010 -815);
WIRE 16 -1 (-1300 -775)(250 -775);
FORCEPROP 2 LAST SIG_NAME SMB_DEBUG_AUX_LVC3_USB_R2_SDA
J 0
(-1010 -765);
DISPLAY 0.851064 (-1010 -765);
WIRE 16 -1 (275 -725)(-1300 -725);
FORCEPROP 2 LAST SIG_NAME DEBUG_PORT_UART_TX
J 0
(-1010 -715);
DISPLAY 0.851064 (-1010 -715);
WIRE 16 -1 (275 -675)(-1300 -675);
FORCEPROP 2 LAST SIG_NAME DEBUG_PORT_UART_RX
J 0
(-1010 -665);
DISPLAY 0.851064 (-1010 -665);
WIRE 16 -1 (2075 -775)(450 -775);
FORCEPROP 2 LAST SIG_NAME SMB_DEBUG_AUX_LVC3_USB_SDA
J 0
(1040 -765);
DISPLAY 0.851064 (1040 -765);
WIRE 16 -1 (2075 -825)(450 -825);
FORCEPROP 2 LAST SIG_NAME SMB_DEBUG_AUX_LVC3_USB_SCL
J 0
(1040 -815);
DISPLAY 0.851064 (1040 -815);
WIRE 16 -1 (-3600 -1175)(-3600 -1075);
FORCEPROP 2 LAST SIG_NAME USB3_MUX_PD
J 0
(-3285 -1065);
DISPLAY 0.851064 (-3285 -1065);
WIRE 16 -1 (-3600 -1075)(-2050 -1075);
WIRE 16 -1 (-3800 -1075)(-3600 -1075);
WIRE 16 -1 (-3800 -825)(-3800 -1075);
WIRE 16 -1 (-2825 -925)(-2050 -925);
FORCEPROP 2 LAST SIG_NAME DEBUG_PORT_PRSNT
J 0
(-2785 -915);
DISPLAY 0.851064 (-2785 -915);
WIRE 16 -1 (-2825 -825)(-2050 -825);
FORCEPROP 2 LAST SIG_NAME USB3_01_MUX_FB_RXN
J 0
(-2835 -815);
DISPLAY 0.808511 (-2835 -815);
WIRE 16 -1 (-2825 -775)(-2050 -775);
FORCEPROP 2 LAST SIG_NAME USB3_01_MUX_FB_RXP
J 0
(-2835 -765);
DISPLAY 0.808511 (-2835 -765);
WIRE 16 -1 (-2050 -725)(-2825 -725);
FORCEPROP 2 LAST SIG_NAME USB3_01_MUX_FB_TXN
J 0
(-2835 -715);
DISPLAY 0.808511 (-2835 -715);
WIRE 16 -1 (-2050 -675)(-2825 -675);
FORCEPROP 2 LAST SIG_NAME USB3_01_MUX_FB_TXP
J 0
(-2835 -665);
DISPLAY 0.808511 (-2835 -665);
WIRE 16 -1 (-2425 25)(-2425 200);
WIRE 16 -1 (-3050 175)(-3050 25);
WIRE 16 -1 (-3050 25)(-2425 25);
WIRE 16 -1 (-3625 25)(-3050 25);
WIRE 16 -1 (-3625 175)(-3625 25);
WIRE 16 -1 (-3625 475)(-3625 375);
WIRE 16 -1 (-3050 475)(-3050 375);
WIRE 16 -1 (-3050 475)(-3625 475);
WIRE 16 -1 (-2425 400)(-2425 475);
WIRE 16 -1 (-2425 475)(-3050 475);
WIRE 16 -1 (-2425 475)(-2150 475);
WIRE 16 -1 (-2050 -425)(-2150 -425);
WIRE 16 -1 (-2150 475)(-2150 -425);
WIRE 16 -1 (-2150 -425)(-2150 -475);
WIRE 16 -1 (-2050 -475)(-2150 -475);
WIRE 16 -1 (-2150 -475)(-2150 -525);
WIRE 16 -1 (-2050 -525)(-2150 -525);
WIRE 16 -1 (-2150 1115)(-1900 1115);
WIRE 16 -1 (-1900 1550)(-1900 1115);
WIRE 16 -1 (-1900 1550)(-2000 1550);
WIRE 16 -1 (-1900 1550)(-1700 1550);
WIRE 16 -1 (-1000 1550)(-1700 1550);
FORCEPROP 2 LAST SIG_NAME USB2_01_F_DP
J 0
(-1585 1560);
DISPLAY 0.808511 (-1585 1560);
WIRE 16 -1 (-1700 1550)(-1700 1150);
WIRE 16 -1 (-1050 1150)(-1700 1150);
WIRE 16 -1 (-900 2075)(-1350 2075);
WIRE 16 -1 (-2000 2850)(-1500 2850);
WIRE 16 -1 (-1350 2375)(-1350 2075);
WIRE 16 -1 (-1275 2375)(-1350 2375);
WIRE 16 -1 (-1350 2375)(-1500 2375);
WIRE 16 -1 (-1500 2850)(-1500 2375);
WIRE 16 -1 (-3000 2375)(-3850 2375);
FORCEPROP 2 LAST SIG_NAME USB3_01_FB_RXN
J 0
(-3825 2385);
DISPLAY 0.808511 (-3825 2385);
WIRE 16 -1 (-3000 2375)(-1500 2375);
WIRE 16 -1 (-3000 2900)(-3000 2375);
WIRE 16 -1 (-2800 2900)(-3000 2900);
WIRE 16 -1 (-3050 2050)(-2550 2050);
WIRE 16 -1 (-3050 1800)(-3475 1800);
FORCEPROP 2 LAST SIG_NAME USB_FPNL_DN
J 0
(-3460 1810);
DISPLAY 0.808511 (-3460 1810);
WIRE 16 -1 (-2800 1800)(-3050 1800);
WIRE 16 -1 (-3050 1800)(-3050 2050);
WIRE 16 -1 (-1300 -425)(-1250 -425);
WIRE 16 -1 (-1250 -425)(-1250 225);
WIRE 16 -1 (-300 225)(-1250 225);
FORCEPROP 2 LAST SIG_NAME USB3_01_TXP_C
J 0
(-1235 235);
DISPLAY 0.808511 (-1235 235);
WIRE 16 -1 (-150 225)(-300 225);
WIRE 16 -1 (-300 225)(-300 500);
WIRE 16 -1 (-300 500)(-150 500);
WIRE 16 -1 (-400 2925)(-800 2925);
WIRE 16 -1 (-400 2925)(-400 2650);
WIRE 16 -1 (-400 2650)(350 2650);
FORCEPROP 2 LAST SIG_NAME USB3_01_MUX_FB_RXP
J 0
(-335 2685);
DISPLAY 0.808511 (-335 2685);
WIRE 16 -1 (-400 2650)(-400 2625);
WIRE 16 -1 (-475 2625)(-400 2625);
WIRE 16 -1 (2375 2275)(1050 2275);
FORCEPROP 2 LAST SIG_NAME SPA_SOUT_SW_DBG
J 0
(1240 2285);
DISPLAY 0.851064 (1240 2285);
WIRE 16 -1 (-1200 -475)(-1300 -475);
WIRE 16 -1 (-1200 50)(-1200 -475);
WIRE 16 -1 (-300 -125)(-150 -125);
WIRE 16 -1 (-150 50)(-300 50);
WIRE 16 -1 (-300 50)(-1200 50);
FORCEPROP 2 LAST SIG_NAME USB3_01_TXN_C
J 0
(-1185 60);
DISPLAY 0.808511 (-1185 60);
WIRE 16 -1 (-300 50)(-300 -125);
WIRE 16 -1 (275 -525)(-1300 -525);
FORCEPROP 2 LAST SIG_NAME USB3_FPNL_RXP
J 0
(-985 -515);
DISPLAY 0.808511 (-985 -515);
WIRE 16 -1 (50 -125)(325 -125);
WIRE 16 -1 (325 -125)(325 50);
WIRE 16 -1 (325 50)(50 50);
WIRE 16 -1 (1075 50)(325 50);
FORCEPROP 2 LAST SIG_NAME USB3_FPNL_TXN
J 2
(1065 60);
DISPLAY 0.808511 (1065 60);
WIRE 16 -1 (275 -575)(-1300 -575);
FORCEPROP 2 LAST SIG_NAME USB3_FPNL_RXN
J 0
(-985 -565);
DISPLAY 0.808511 (-985 -565);
WIRE 16 -1 (2850 3725)(2850 4350);
WIRE 16 -1 (2850 4350)(3500 4350);
FORCEPROP 2 LAST SIG_NAME DEBUG_PORT_PRSNT
J 0
(2865 4385);
DISPLAY 0.851064 (2865 4385);
WIRE 16 -1 (4375 -1500)(3600 -1500);
FORCEPROP 2 LAST SIG_NAME DEBUG_PORT_PRSNT
J 2
(4335 -1490);
DISPLAY 0.851064 (4335 -1490);
WIRE 16 -1 (-375 4250)(-675 4250);
WIRE 16 -1 (-375 4250)(-375 3950);
WIRE 16 -1 (-375 3950)(425 3950);
FORCEPROP 2 LAST SIG_NAME USB3_01_MUX_FB_TXP
J 0
(-260 3985);
DISPLAY 0.808511 (-260 3985);
WIRE 16 -1 (-450 3950)(-375 3950);
DOT 1 (1150 1625);
DOT 1 (-1775 1800);
DOT 1 (825 1625);
DOT 1 (1150 1225);
DOT 1 (-1900 1800);
DOT 1 (-1900 1550);
DOT 1 (-1700 1550);
DOT 1 (-1925 3200);
DOT 1 (-3250 3950);
DOT 1 (1400 1625);
DOT 1 (-1750 3950);
DOT 1 (-1650 3700);
DOT 1 (-1575 2625);
DOT 1 (-1500 2375);
DOT 1 (-3000 2375);
DOT 1 (-3100 2625);
DOT 1 (-3175 3700);
DOT 1 (-1350 2375);
DOT 1 (-1350 2625);
DOT 1 (-400 2375);
DOT 1 (-400 2650);
DOT 1 (-1325 3700);
DOT 1 (-1325 3950);
DOT 1 (-375 3700);
DOT 1 (-375 3950);
DOT 1 (-3050 1800);
DOT 1 (-1100 -1175);
DOT 1 (-2150 475);
DOT 1 (4650 -450);
DOT 1 (-1100 -1225);
DOT 1 (-3600 -1075);
DOT 1 (-3050 25);
DOT 1 (-2425 25);
DOT 1 (-3050 475);
DOT 1 (-2425 475);
DOT 1 (-2150 -425);
DOT 1 (-2150 -475);
DOT 1 (1400 1225);
DOT 1 (1750 1225);
DOT 1 (4875 325);
DOT 1 (3775 375);
DOT 1 (-3050 1550);
DOT 1 (3225 4075);
DOT 1 (1275 3475);
DOT 1 (4100 2275);
DOT 1 (4225 3475);
DOT 1 (2300 2850);
DOT 1 (325 225);
DOT 1 (325 50);
DOT 1 (-300 225);
DOT 1 (-300 50);
FORCENOTE
CAD NOTE: PLACE AS CLOSE AS POSSIBLE TO USB CONNECTOR
(175 800) 0;
DISPLAY LEFT (175 800);
DISPLAY 0.808511 (175 800);
PAINT WHITE (175 800);
QUIT
